FILE_TYPE = MACRO_DRAWING;
SET COLOR_WIRE YELLOW;
SET COLOR_PROP ORANGE;
SET COLOR_DOT WHITE;
SET COLOR_ARC YELLOW;
SET COLOR_BODY GREEN;
SET COLOR_NOTE PURPLE;
SET PROP_DISPLAY VALUE;
SET PAGE_NUMBER P325;
FORCEADD UNIVERSAL_GND..1
(-2700 -2250);
FORCEPROP 3 LASTPIN (-2700 -2200) SIG_NAME AGND_HSC\g
J 0
(-2690 -2190);
DISPLAY 0.659574 (-2690 -2190);
PAINT MONO (-2690 -2190);
DISPLAY INVISIBLE (-2690 -2190);
FORCEPROP 1 LAST HDL_POWER AGND_HSC
J 1
(-2675 -2325);
DISPLAY 0.723404 (-2675 -2325);
PAINT GREEN (-2675 -2325);
FORCEPROP 2 LAST CDS_LIB pure_quanta_power
J 0
(-2700 -2250);
DISPLAY INVISIBLE (-2700 -2250);
FORCEPROP 1 LAST PATH I1
J 0
(-2625 -2250);
DISPLAY 0.872340 (-2625 -2250);
PAINT AQUA (-2625 -2250);
DISPLAY INVISIBLE (-2625 -2250);
FORCEADD OFFPAGE..4
R 2
(-2025 -1300);
FORCEPROP 2 LAST $XR2 265 
J 0
(-2517 -1300);
DISPLAY 0.638298 (-2517 -1300);
PAINT MONO (-2517 -1300);
FORCEPROP 2 LAST $XR1 264 
J 0
(-2397 -1300);
DISPLAY 0.638298 (-2397 -1300);
PAINT MONO (-2397 -1300);
FORCEPROP 2 LAST $XR0 263 
J 0
(-2277 -1300);
DISPLAY 0.638298 (-2277 -1300);
PAINT MONO (-2277 -1300);
FORCEPROP 2 LAST CDS_LIB standard
J 0
(-2025 -1300);
DISPLAY INVISIBLE (-2025 -1300);
FORCEPROP 1 LAST OFFPAGE TRUE
J 2
(-2350 -1425);
DISPLAY 0.872340 (-2350 -1425);
PAINT GREEN (-2350 -1425);
DISPLAY INVISIBLE (-2350 -1425);
FORCEPROP 1 LAST COMMENT_BODY TRUE
J 2
(-2000 -1400);
DISPLAY 0.872340 (-2000 -1400);
PAINT GREEN (-2000 -1400);
DISPLAY INVISIBLE (-2000 -1400);
FORCEPROP 2 LAST PATH I10
J 0
(-2275 -1250);
DISPLAY 1.021277 (-2275 -1250);
DISPLAY INVISIBLE (-2275 -1250);
FORCEADD Q_RES..1
(-1900 -1125);
FORCEPROP 1 LAST LOCATION PR3984
J 0
(-2200 -1125);
DISPLAY 0.723404 (-2200 -1125);
PAINT AQUA (-2200 -1125);
FORCEPROP 0 LAST $SEC 1
J 0
(-1850 -1050);
DISPLAY 0.680851 (-1850 -1050);
PAINT MONO (-1850 -1050);
DISPLAY INVISIBLE (-1850 -1050);
FORCEPROP 0 LAST CDS_SEC 1
J 0
(-1850 -1050);
DISPLAY 1.021277 (-1850 -1050);
DISPLAY INVISIBLE (-1850 -1050);
FORCEPROP 1 LASTPIN (-2000 -1125) $PN 1
J 0
(-1988 -1113);
DISPLAY 0.787234 (-1988 -1113);
PAINT MONO (-1988 -1113);
FORCEPROP 1 LASTPIN (-1800 -1125) $PN 2
J 0
(-1838 -1113);
DISPLAY 0.787234 (-1838 -1113);
PAINT MONO (-1838 -1113);
FORCEPROP 0 LAST ROOM HSC BOM1
J 0
(-2500 -1125);
DISPLAY 0.680851 (-2500 -1125);
FORCEPROP 1 LAST VALUE 120K
J 2
(-1925 -1200);
DISPLAY 0.723404 (-1925 -1200);
PAINT SKYBLUE (-1925 -1200);
FORCEPROP 1 LAST TOLERANCE 1%
J 0
(-1875 -1200);
DISPLAY 0.723404 (-1875 -1200);
PAINT SKYBLUE (-1875 -1200);
FORCEPROP 1 LAST PACK_TYPE 0402LF
J 0
(-1775 -1200);
DISPLAY 0.723404 (-1775 -1200);
PAINT SKYBLUE (-1775 -1200);
FORCEPROP 1 LAST MATERIAL CHIP
J 0
(-1850 -1250);
DISPLAY 0.723404 (-1850 -1250);
PAINT SKYBLUE (-1850 -1250);
FORCEPROP 1 LAST WATTAGE 1/16W
J 2
(-1875 -1250);
DISPLAY 0.723404 (-1875 -1250);
PAINT SKYBLUE (-1875 -1250);
FORCEPROP 2 LAST CDS_LIB pure_quanta
J 0
(-1900 -1125);
DISPLAY INVISIBLE (-1900 -1125);
FORCEPROP 1 LAST PATH I11
J 0
(-1950 -975);
DISPLAY 0.978723 (-1950 -975);
PAINT WHITE (-1950 -975);
DISPLAY INVISIBLE (-1950 -975);
FORCEPROP 1 LAST PART_NUMBER CS41202FB05
J 0
(-1775 -1125);
DISPLAY 0.723404 (-1775 -1125);
PAINT WHITE (-1775 -1125);
DISPLAY INVISIBLE (-1775 -1125);
FORCEADD Q_CAP..1
(-1975 -1950);
FORCEPROP 1 LAST LOCATION PC2349
J 0
(-1900 -1850);
DISPLAY 0.808511 (-1900 -1850);
PAINT AQUA (-1900 -1850);
FORCEPROP 0 LAST $SEC 1
J 0
(-1900 -1800);
DISPLAY 0.680851 (-1900 -1800);
PAINT MONO (-1900 -1800);
DISPLAY INVISIBLE (-1900 -1800);
FORCEPROP 0 LAST CDS_SEC 1
J 0
(-1900 -1800);
DISPLAY 1.021277 (-1900 -1800);
DISPLAY INVISIBLE (-1900 -1800);
FORCEPROP 1 LASTPIN (-1975 -1850) $PN 1
J 0
(-1965 -1870);
DISPLAY 0.787234 (-1965 -1870);
PAINT MONO (-1965 -1870);
FORCEPROP 1 LASTPIN (-1975 -2050) $PN 2
J 0
(-1965 -2070);
DISPLAY 0.787234 (-1965 -2070);
PAINT MONO (-1965 -2070);
FORCEPROP 1 LAST PACK_TYPE 0402
J 0
(-1900 -2100);
DISPLAY 0.723404 (-1900 -2100);
PAINT SKYBLUE (-1900 -2100);
FORCEPROP 1 LAST VALUE 1NF
J 0
(-1900 -1900);
DISPLAY 0.723404 (-1900 -1900);
PAINT SKYBLUE (-1900 -1900);
FORCEPROP 1 LAST MATERIAL EMPTY
J 0
(-1900 -2000);
DISPLAY 0.723404 (-1900 -2000);
PAINT RED (-1900 -2000);
FORCEPROP 1 LAST VOLTAGE 50V
J 0
(-1900 -1950);
DISPLAY 0.723404 (-1900 -1950);
PAINT SKYBLUE (-1900 -1950);
FORCEPROP 0 LAST ROOM HSC BOM1
J 0
(-1900 -1800);
DISPLAY 0.680851 (-1900 -1800);
FORCEPROP 2 LAST CDS_LIB pure_quanta
J 0
(-1975 -1950);
DISPLAY INVISIBLE (-1975 -1950);
FORCEPROP 1 LAST TOLERANCE 10%
J 0
(-1925 -2000);
DISPLAY 0.978723 (-1925 -2000);
PAINT SKYBLUE (-1925 -2000);
DISPLAY INVISIBLE (-1925 -2000);
FORCEPROP 1 LAST PATH I12
J 0
(-1925 -1800);
DISPLAY 0.978723 (-1925 -1800);
PAINT WHITE (-1925 -1800);
DISPLAY INVISIBLE (-1925 -1800);
FORCEPROP 1 LAST PART_NUMBER CH21006KB16
J 0
(-1900 -2050);
DISPLAY 0.723404 (-1900 -2050);
PAINT WHITE (-1900 -2050);
DISPLAY INVISIBLE (-1900 -2050);
FORCEADD Q_RES..2
(-1475 -1950);
FORCEPROP 1 LAST LOCATION PR3987
J 0
(-1420 -1800);
DISPLAY 0.723404 (-1420 -1800);
PAINT AQUA (-1420 -1800);
FORCEPROP 0 LAST $SEC 1
J 0
(-1400 -1750);
DISPLAY 0.680851 (-1400 -1750);
PAINT MONO (-1400 -1750);
DISPLAY INVISIBLE (-1400 -1750);
FORCEPROP 0 LAST CDS_SEC 1
J 0
(-1400 -1750);
DISPLAY 1.021277 (-1400 -1750);
DISPLAY INVISIBLE (-1400 -1750);
FORCEPROP 1 LASTPIN (-1475 -1850) $PN 1
J 0
(-1470 -1888);
DISPLAY 0.787234 (-1470 -1888);
PAINT MONO (-1470 -1888);
FORCEPROP 1 LASTPIN (-1475 -2050) $PN 2
J 0
(-1470 -2040);
DISPLAY 0.787234 (-1470 -2040);
PAINT MONO (-1470 -2040);
FORCEPROP 1 LAST MATERIAL CHIP
J 0
(-1425 -2000);
DISPLAY 0.723404 (-1425 -2000);
PAINT SKYBLUE (-1425 -2000);
FORCEPROP 1 LAST VALUE 2K
J 0
(-1420 -1850);
DISPLAY 0.723404 (-1420 -1850);
PAINT SKYBLUE (-1420 -1850);
FORCEPROP 1 LAST TOLERANCE 0.1%
J 0
(-1420 -1900);
DISPLAY 0.723404 (-1420 -1900);
PAINT SKYBLUE (-1420 -1900);
FORCEPROP 0 LAST ROOM HSC BOM1
J 0
(-1425 -2175);
DISPLAY 0.680851 (-1425 -2175);
FORCEPROP 1 LAST PACK_TYPE 0402LF
J 0
(-1425 -2100);
DISPLAY 0.723404 (-1425 -2100);
PAINT SKYBLUE (-1425 -2100);
FORCEPROP 1 LAST WATTAGE 1/16W
J 0
(-1425 -1950);
DISPLAY 0.723404 (-1425 -1950);
PAINT SKYBLUE (-1425 -1950);
FORCEPROP 2 LAST CDS_LIB pure_quanta
J 0
(-1475 -1950);
DISPLAY INVISIBLE (-1475 -1950);
FORCEPROP 1 LAST PATH I13
J 0
(-1425 -1775);
DISPLAY 0.978723 (-1425 -1775);
PAINT WHITE (-1425 -1775);
DISPLAY INVISIBLE (-1425 -1775);
FORCEPROP 1 LAST PART_NUMBER CS22002BB07
J 0
(-1425 -2050);
DISPLAY 0.723404 (-1425 -2050);
PAINT WHITE (-1425 -2050);
DISPLAY INVISIBLE (-1425 -2050);
FORCEADD Q_RES..2
(-950 -1950);
FORCEPROP 1 LAST LOCATION PR3991
J 0
(-895 -1800);
DISPLAY 0.723404 (-895 -1800);
PAINT AQUA (-895 -1800);
FORCEPROP 0 LAST $SEC 1
J 0
(-875 -1750);
DISPLAY 0.680851 (-875 -1750);
PAINT MONO (-875 -1750);
DISPLAY INVISIBLE (-875 -1750);
FORCEPROP 0 LAST CDS_SEC 1
J 0
(-875 -1750);
DISPLAY 1.021277 (-875 -1750);
DISPLAY INVISIBLE (-875 -1750);
FORCEPROP 1 LASTPIN (-950 -1850) $PN 1
J 0
(-945 -1888);
DISPLAY 0.787234 (-945 -1888);
PAINT MONO (-945 -1888);
FORCEPROP 1 LASTPIN (-950 -2050) $PN 2
J 0
(-945 -2040);
DISPLAY 0.787234 (-945 -2040);
PAINT MONO (-945 -2040);
FORCEPROP 1 LAST WATTAGE 1/16W
J 0
(-900 -1950);
DISPLAY 0.723404 (-900 -1950);
PAINT SKYBLUE (-900 -1950);
FORCEPROP 1 LAST MATERIAL CHIP
J 0
(-900 -2000);
DISPLAY 0.723404 (-900 -2000);
PAINT SKYBLUE (-900 -2000);
FORCEPROP 1 LAST PACK_TYPE 0402LF
J 0
(-900 -2100);
DISPLAY 0.723404 (-900 -2100);
PAINT SKYBLUE (-900 -2100);
FORCEPROP 1 LAST VALUE 2K
J 0
(-895 -1850);
DISPLAY 0.723404 (-895 -1850);
PAINT SKYBLUE (-895 -1850);
FORCEPROP 1 LAST TOLERANCE 0.1%
J 0
(-895 -1900);
DISPLAY 0.723404 (-895 -1900);
PAINT SKYBLUE (-895 -1900);
FORCEPROP 0 LAST ROOM HSC BOM1
J 0
(-900 -2175);
DISPLAY 0.680851 (-900 -2175);
FORCEPROP 2 LAST CDS_LIB pure_quanta
J 0
(-950 -1950);
DISPLAY INVISIBLE (-950 -1950);
FORCEPROP 1 LAST PATH I14
J 0
(-900 -1775);
DISPLAY 0.978723 (-900 -1775);
PAINT WHITE (-900 -1775);
DISPLAY INVISIBLE (-900 -1775);
FORCEPROP 1 LAST PART_NUMBER CS22002BB07
J 0
(-900 -2050);
DISPLAY 0.723404 (-900 -2050);
PAINT WHITE (-900 -2050);
DISPLAY INVISIBLE (-900 -2050);
FORCEADD OFFPAGE..5
(-1050 -1725);
FORCEPROP 2 LAST $XR2 263 
J 0
(-1305 -1761);
DISPLAY 0.638298 (-1305 -1761);
PAINT MONO (-1305 -1761);
FORCEPROP 2 LAST $XR1 265 
J 0
(-1425 -1725);
DISPLAY 0.638298 (-1425 -1725);
PAINT MONO (-1425 -1725);
FORCEPROP 2 LAST $XR0 264 
J 0
(-1305 -1725);
DISPLAY 0.638298 (-1305 -1725);
PAINT MONO (-1305 -1725);
FORCEPROP 2 LAST CDS_LIB standard
J 0
(-1050 -1725);
DISPLAY INVISIBLE (-1050 -1725);
FORCEPROP 1 LAST OFFPAGE TRUE
J 0
(-725 -1850);
DISPLAY 0.872340 (-725 -1850);
PAINT AQUA (-725 -1850);
DISPLAY INVISIBLE (-725 -1850);
FORCEPROP 1 LAST COMMENT_BODY TRUE
J 0
(-950 -1800);
DISPLAY 1.170213 (-950 -1800);
PAINT GREEN (-950 -1800);
DISPLAY INVISIBLE (-950 -1800);
FORCEPROP 2 LAST PATH I15
J 0
(-1300 -1675);
DISPLAY 1.021277 (-1300 -1675);
DISPLAY INVISIBLE (-1300 -1675);
FORCEADD Q_RES..1
(-1300 -1300);
FORCEPROP 1 LAST LOCATION PR3989
J 0
(-1600 -1300);
DISPLAY 0.723404 (-1600 -1300);
PAINT AQUA (-1600 -1300);
FORCEPROP 0 LAST $SEC 1
J 0
(-1175 -1225);
DISPLAY 0.680851 (-1175 -1225);
PAINT MONO (-1175 -1225);
DISPLAY INVISIBLE (-1175 -1225);
FORCEPROP 0 LAST CDS_SEC 1
J 0
(-1175 -1225);
DISPLAY 1.021277 (-1175 -1225);
DISPLAY INVISIBLE (-1175 -1225);
FORCEPROP 1 LASTPIN (-1400 -1300) $PN 1
J 0
(-1388 -1288);
DISPLAY 0.787234 (-1388 -1288);
PAINT MONO (-1388 -1288);
FORCEPROP 1 LASTPIN (-1200 -1300) $PN 2
J 0
(-1238 -1288);
DISPLAY 0.787234 (-1238 -1288);
PAINT MONO (-1238 -1288);
FORCEPROP 0 LAST ROOM HSC BOM1
J 0
(-1375 -1225);
DISPLAY 0.553191 (-1375 -1225);
FORCEPROP 1 LAST WATTAGE 1/16W
J 2
(-1425 -1400);
DISPLAY 0.723404 (-1425 -1400);
PAINT SKYBLUE (-1425 -1400);
FORCEPROP 1 LAST TOLERANCE 5%
J 0
(-1175 -1350);
DISPLAY 0.723404 (-1175 -1350);
PAINT SKYBLUE (-1175 -1350);
FORCEPROP 1 LAST VALUE 0
J 2
(-1125 -1275);
DISPLAY 0.723404 (-1125 -1275);
PAINT SKYBLUE (-1125 -1275);
FORCEPROP 1 LAST MATERIAL CHIP
J 0
(-1150 -1400);
DISPLAY 0.723404 (-1150 -1400);
PAINT SKYBLUE (-1150 -1400);
FORCEPROP 1 LAST PACK_TYPE 0402LF
J 0
(-1375 -1400);
DISPLAY 0.723404 (-1375 -1400);
PAINT SKYBLUE (-1375 -1400);
FORCEPROP 2 LAST CDS_LIB pure_quanta
J 0
(-1300 -1300);
DISPLAY INVISIBLE (-1300 -1300);
FORCEPROP 1 LAST PATH I16
J 0
(-1350 -1150);
DISPLAY 0.978723 (-1350 -1150);
PAINT WHITE (-1350 -1150);
DISPLAY INVISIBLE (-1350 -1150);
FORCEPROP 1 LAST PART_NUMBER CS00002JB13
J 0
(-1625 -1350);
DISPLAY 0.723404 (-1625 -1350);
PAINT WHITE (-1625 -1350);
DISPLAY INVISIBLE (-1625 -1350);
FORCEADD MP5991GLUZ..1
(25 -1200);
FORCEPROP 1 LAST LOCATION PU297
J 0
(-300 -200);
DISPLAY 1.148936 (-300 -200);
PAINT GREEN (-300 -200);
FORCEPROP 2 LAST SEC 1
J 0
(-275 25);
DISPLAY 0.680851 (-275 25);
PAINT MONO (-275 25);
DISPLAY INVISIBLE (-275 25);
FORCEPROP 2 LASTPIN (-450 -1625) $PN 23
J 2
(-460 -1615);
DISPLAY 0.680851 (-460 -1615);
PAINT MONO (-460 -1615);
FORCEPROP 2 LASTPIN (500 -1275) $PN 3
J 0
(510 -1265);
DISPLAY 0.680851 (510 -1265);
PAINT MONO (510 -1265);
FORCEPROP 2 LASTPIN (500 -1375) $PN 6
J 0
(510 -1365);
DISPLAY 0.680851 (510 -1365);
PAINT MONO (510 -1365);
FORCEPROP 2 LASTPIN (-450 -1925) $PN 20
J 2
(-460 -1915);
DISPLAY 0.680851 (-460 -1915);
PAINT MONO (-460 -1915);
FORCEPROP 2 LASTPIN (500 -1575) $PN 5
J 0
(510 -1565);
DISPLAY 0.680851 (510 -1565);
PAINT MONO (510 -1565);
FORCEPROP 2 LASTPIN (-450 -1725) $PN 22
J 2
(-460 -1715);
DISPLAY 0.680851 (-460 -1715);
PAINT MONO (-460 -1715);
FORCEPROP 2 LASTPIN (-450 -1125) $PN 8
J 2
(-460 -1115);
DISPLAY 0.680851 (-460 -1115);
PAINT MONO (-460 -1115);
FORCEPROP 2 LASTPIN (500 -1475) $PN 7
J 0
(510 -1465);
DISPLAY 0.680851 (510 -1465);
PAINT MONO (510 -1465);
FORCEPROP 2 LASTPIN (-450 -1525) $PN 24
J 2
(-460 -1515);
DISPLAY 0.680851 (-460 -1515);
PAINT MONO (-460 -1515);
FORCEPROP 2 LASTPIN (-450 -1425) $PN 4
J 2
(-460 -1415);
DISPLAY 0.680851 (-460 -1415);
PAINT MONO (-460 -1415);
FORCEPROP 2 LASTPIN (-450 -1225) $PN 17
J 2
(-460 -1215);
DISPLAY 0.680851 (-460 -1215);
PAINT MONO (-460 -1215);
FORCEPROP 2 LASTPIN (500 -1775) $PN 19
J 0
(510 -1765);
DISPLAY 0.680851 (510 -1765);
PAINT MONO (510 -1765);
FORCEPROP 2 LASTPIN (-450 -1025) $PN 21
J 2
(-460 -1015);
DISPLAY 0.680851 (-460 -1015);
PAINT MONO (-460 -1015);
FORCEPROP 2 LASTPIN (-450 -475) $PN 9
J 2
(-460 -465);
DISPLAY 0.680851 (-460 -465);
PAINT MONO (-460 -465);
FORCEPROP 2 LASTPIN (-450 -525) $PN 10
J 2
(-460 -515);
DISPLAY 0.680851 (-460 -515);
PAINT MONO (-460 -515);
FORCEPROP 2 LASTPIN (-450 -575) $PN 11
J 2
(-460 -565);
DISPLAY 0.680851 (-460 -565);
PAINT MONO (-460 -565);
FORCEPROP 2 LASTPIN (-450 -625) $PN 12
J 2
(-460 -615);
DISPLAY 0.680851 (-460 -615);
PAINT MONO (-460 -615);
FORCEPROP 2 LASTPIN (-450 -675) $PN 13
J 2
(-460 -665);
DISPLAY 0.680851 (-460 -665);
PAINT MONO (-460 -665);
FORCEPROP 2 LASTPIN (-450 -725) $PN 14
J 2
(-460 -715);
DISPLAY 0.680851 (-460 -715);
PAINT MONO (-460 -715);
FORCEPROP 2 LASTPIN (-450 -775) $PN 15
J 2
(-460 -765);
DISPLAY 0.680851 (-460 -765);
PAINT MONO (-460 -765);
FORCEPROP 2 LASTPIN (-450 -825) $PN 16
J 2
(-460 -815);
DISPLAY 0.680851 (-460 -815);
PAINT MONO (-460 -815);
FORCEPROP 2 LASTPIN (-450 -875) $PN 33
J 2
(-460 -865);
DISPLAY 0.680851 (-460 -865);
PAINT MONO (-460 -865);
FORCEPROP 2 LASTPIN (500 -475) $PN 1
J 0
(510 -465);
DISPLAY 0.680851 (510 -465);
PAINT MONO (510 -465);
FORCEPROP 2 LASTPIN (500 -525) $PN 2
J 0
(510 -515);
DISPLAY 0.680851 (510 -515);
PAINT MONO (510 -515);
FORCEPROP 2 LASTPIN (500 -575) $PN 25
J 0
(510 -565);
DISPLAY 0.680851 (510 -565);
PAINT MONO (510 -565);
FORCEPROP 2 LASTPIN (500 -625) $PN 26
J 0
(510 -615);
DISPLAY 0.680851 (510 -615);
PAINT MONO (510 -615);
FORCEPROP 2 LASTPIN (500 -675) $PN 27
J 0
(510 -665);
DISPLAY 0.680851 (510 -665);
PAINT MONO (510 -665);
FORCEPROP 2 LASTPIN (500 -725) $PN 28
J 0
(510 -715);
DISPLAY 0.680851 (510 -715);
PAINT MONO (510 -715);
FORCEPROP 2 LASTPIN (500 -775) $PN 29
J 0
(510 -765);
DISPLAY 0.680851 (510 -765);
PAINT MONO (510 -765);
FORCEPROP 2 LASTPIN (500 -825) $PN 30
J 0
(510 -815);
DISPLAY 0.680851 (510 -815);
PAINT MONO (510 -815);
FORCEPROP 2 LASTPIN (500 -875) $PN 31
J 0
(510 -865);
DISPLAY 0.680851 (510 -865);
PAINT MONO (510 -865);
FORCEPROP 2 LASTPIN (500 -925) $PN 32
J 0
(510 -915);
DISPLAY 0.680851 (510 -915);
PAINT MONO (510 -915);
FORCEPROP 2 LASTPIN (500 -1675) $PN 18
J 0
(510 -1665);
DISPLAY 0.680851 (510 -1665);
PAINT MONO (510 -1665);
FORCEPROP 1 LAST MATERIAL IC
J 0
(-300 -400);
DISPLAY 0.723404 (-300 -400);
PAINT GREEN (-300 -400);
FORCEPROP 2 LAST PART_TYPE SMLF
J 0
(-300 -250);
DISPLAY 1.021277 (-300 -250);
FORCEPROP 0 LAST ROOM HSC BOM1
J 0
(-300 -75);
DISPLAY 0.680851 (-300 -75);
FORCEPROP 2 LAST VALUE MP5991GLU-Z
J 0
(-300 -300);
DISPLAY 1.021277 (-300 -300);
FORCEPROP 2 LAST SEC_TYPE 
J 0
(-275 25);
DISPLAY 1.021277 (-275 25);
DISPLAY INVISIBLE (-275 25);
FORCEPROP 2 LAST CDS_LIB pure_quanta
J 0
(25 -1200);
DISPLAY INVISIBLE (25 -1200);
FORCEPROP 1 LAST CDS_LMAN_SYM_OUTLINE -325,775,325,-775
J 0
(25 -1200);
DISPLAY 0.468085 (25 -1200);
PAINT GREEN (25 -1200);
DISPLAY INVISIBLE (25 -1200);
FORCEPROP 1 LAST NEEDS_NO_SIZE TRUE
J 0
(25 -1200);
DISPLAY 0.723404 (25 -1200);
PAINT GREEN (25 -1200);
DISPLAY INVISIBLE (25 -1200);
FORCEPROP 1 LAST PATH I17
J 0
(25 -1200);
DISPLAY 0.723404 (25 -1200);
PAINT GREEN (25 -1200);
DISPLAY INVISIBLE (25 -1200);
FORCEPROP 1 LAST PART_NUMBER AL005991A00
J 0
(-300 -350);
DISPLAY 0.723404 (-300 -350);
PAINT GREEN (-300 -350);
DISPLAY INVISIBLE (-300 -350);
FORCEADD UNIVERSAL_POWER..1
(-950 -325);
FORCEPROP 3 LASTPIN (-950 -375) SIG_NAME P12V_PSU\g
J 0
(-940 -365);
DISPLAY 0.659574 (-940 -365);
PAINT MONO (-940 -365);
DISPLAY INVISIBLE (-940 -365);
FORCEPROP 1 LAST HDL_POWER P12V_PSU
J 1
(-950 -275);
DISPLAY 0.723404 (-950 -275);
PAINT GREEN (-950 -275);
FORCEPROP 2 LAST BOM_COST MIO_VRD_SB
J 0
(-950 -225);
DISPLAY 0.617021 (-950 -225);
PAINT PURPLE (-950 -225);
DISPLAY INVISIBLE (-950 -225);
FORCEPROP 2 LAST CDS_LIB pure_quanta_power
J 0
(-950 -325);
DISPLAY INVISIBLE (-950 -325);
FORCEPROP 1 LAST PATH I18
J 0
(-900 -300);
DISPLAY 0.872340 (-900 -300);
PAINT AQUA (-900 -300);
DISPLAY INVISIBLE (-900 -300);
FORCEADD UNIVERSAL_GND..1
(-3600 1175);
FORCEPROP 3 LASTPIN (-3600 1225) SIG_NAME AGND_HSC\g
J 0
(-3590 1235);
DISPLAY 0.659574 (-3590 1235);
PAINT MONO (-3590 1235);
DISPLAY INVISIBLE (-3590 1235);
FORCEPROP 1 LAST HDL_POWER AGND_HSC
J 1
(-3575 1100);
DISPLAY 0.723404 (-3575 1100);
PAINT GREEN (-3575 1100);
FORCEPROP 2 LAST CDS_LIB pure_quanta_power
J 0
(-3600 1175);
DISPLAY INVISIBLE (-3600 1175);
FORCEPROP 1 LAST PATH I19
J 0
(-3525 1175);
DISPLAY 0.872340 (-3525 1175);
PAINT AQUA (-3525 1175);
DISPLAY INVISIBLE (-3525 1175);
FORCEADD Q_CAP..1
(-2700 -1950);
FORCEPROP 1 LAST LOCATION PC2225
J 0
(-2625 -1850);
DISPLAY 0.723404 (-2625 -1850);
PAINT AQUA (-2625 -1850);
FORCEPROP 0 LAST $SEC 1
J 0
(-2625 -1800);
DISPLAY 0.680851 (-2625 -1800);
PAINT MONO (-2625 -1800);
DISPLAY INVISIBLE (-2625 -1800);
FORCEPROP 0 LAST CDS_SEC 1
J 0
(-2625 -1800);
DISPLAY 1.021277 (-2625 -1800);
DISPLAY INVISIBLE (-2625 -1800);
FORCEPROP 1 LASTPIN (-2700 -1850) $PN 1
J 0
(-2690 -1870);
DISPLAY 0.787234 (-2690 -1870);
PAINT MONO (-2690 -1870);
FORCEPROP 1 LASTPIN (-2700 -2050) $PN 2
J 0
(-2690 -2070);
DISPLAY 0.787234 (-2690 -2070);
PAINT MONO (-2690 -2070);
FORCEPROP 1 LAST PACK_TYPE 0402
J 0
(-2625 -2100);
DISPLAY 0.723404 (-2625 -2100);
PAINT SKYBLUE (-2625 -2100);
FORCEPROP 1 LAST MATERIAL EMPTY
J 0
(-2625 -2000);
DISPLAY 0.723404 (-2625 -2000);
PAINT RED (-2625 -2000);
FORCEPROP 1 LAST VALUE 220PF
J 0
(-2625 -1900);
DISPLAY 0.723404 (-2625 -1900);
PAINT SKYBLUE (-2625 -1900);
FORCEPROP 1 LAST VOLTAGE 50V
J 0
(-2625 -1950);
DISPLAY 0.723404 (-2625 -1950);
PAINT SKYBLUE (-2625 -1950);
FORCEPROP 0 LAST ROOM HSC BOM1
J 0
(-2625 -1800);
DISPLAY 0.680851 (-2625 -1800);
FORCEPROP 1 LAST TOLERANCE 10%
J 0
(-2650 -2000);
DISPLAY 0.978723 (-2650 -2000);
PAINT SKYBLUE (-2650 -2000);
DISPLAY INVISIBLE (-2650 -2000);
FORCEPROP 2 LAST CDS_LIB pure_quanta
J 0
(-2700 -1950);
DISPLAY INVISIBLE (-2700 -1950);
FORCEPROP 1 LAST PATH I2
J 0
(-2650 -1800);
DISPLAY 0.978723 (-2650 -1800);
PAINT WHITE (-2650 -1800);
DISPLAY INVISIBLE (-2650 -1800);
FORCEPROP 1 LAST PART_NUMBER TMP_QCH12206KB14
J 0
(-2625 -2050);
DISPLAY 0.723404 (-2625 -2050);
PAINT WHITE (-2625 -2050);
DISPLAY INVISIBLE (-2625 -2050);
FORCEADD Q_CAP..1
(-3600 1475);
FORCEPROP 1 LAST LOCATION PC3272
J 0
(-3525 1625);
DISPLAY 0.723404 (-3525 1625);
PAINT AQUA (-3525 1625);
FORCEPROP 0 LAST $SEC 1
J 0
(-3525 1675);
DISPLAY 0.680851 (-3525 1675);
PAINT MONO (-3525 1675);
DISPLAY INVISIBLE (-3525 1675);
FORCEPROP 0 LAST CDS_SEC 1
J 0
(-3525 1675);
DISPLAY 1.021277 (-3525 1675);
DISPLAY INVISIBLE (-3525 1675);
FORCEPROP 1 LASTPIN (-3600 1575) $PN 1
J 0
(-3590 1555);
DISPLAY 0.787234 (-3590 1555);
PAINT MONO (-3590 1555);
FORCEPROP 1 LASTPIN (-3600 1375) $PN 2
J 0
(-3590 1355);
DISPLAY 0.787234 (-3590 1355);
PAINT MONO (-3590 1355);
FORCEPROP 1 LAST VOLTAGE 25V
J 0
(-3525 1525);
DISPLAY 0.723404 (-3525 1525);
PAINT SKYBLUE (-3525 1525);
FORCEPROP 1 LAST MATERIAL X6S
J 0
(-3525 1475);
DISPLAY 0.723404 (-3525 1475);
PAINT SKYBLUE (-3525 1475);
FORCEPROP 0 LAST ROOM HSC BOM1
J 0
(-3525 1675);
DISPLAY 0.680851 (-3525 1675);
FORCEPROP 1 LAST PACK_TYPE C0402
J 0
(-3525 1375);
DISPLAY 0.723404 (-3525 1375);
PAINT SKYBLUE (-3525 1375);
FORCEPROP 1 LAST VALUE 1UF
J 0
(-3525 1575);
DISPLAY 0.723404 (-3525 1575);
PAINT SKYBLUE (-3525 1575);
FORCEPROP 2 LAST CDS_LIB pure_quanta
J 0
(-3600 1475);
DISPLAY INVISIBLE (-3600 1475);
FORCEPROP 1 LAST TOLERANCE 10%
J 0
(-3550 1425);
DISPLAY 0.978723 (-3550 1425);
PAINT SKYBLUE (-3550 1425);
DISPLAY INVISIBLE (-3550 1425);
FORCEPROP 1 LAST PATH I20
J 0
(-3550 1625);
DISPLAY 0.978723 (-3550 1625);
PAINT WHITE (-3550 1625);
DISPLAY INVISIBLE (-3550 1625);
FORCEPROP 1 LAST PART_NUMBER CH5104KEB02
J 0
(-3525 1425);
DISPLAY 0.723404 (-3525 1425);
PAINT WHITE (-3525 1425);
DISPLAY INVISIBLE (-3525 1425);
FORCEADD Q_RES..1
R 1
(-3600 1950);
FORCEPROP 1 LAST LOCATION PR3980
J 0
(-3525 2100);
DISPLAY 0.723404 (-3525 2100);
PAINT AQUA (-3525 2100);
FORCEPROP 0 LAST $SEC 1
R 1
J 0
(-3525 2150);
DISPLAY 0.680851 (-3525 2150);
PAINT MONO (-3525 2150);
DISPLAY INVISIBLE (-3525 2150);
FORCEPROP 0 LAST CDS_SEC 1
R 1
J 0
(-3525 2150);
DISPLAY 1.021277 (-3525 2150);
DISPLAY INVISIBLE (-3525 2150);
FORCEPROP 1 LASTPIN (-3600 1850) $PN 1
R 1
J 0
(-3612 1862);
DISPLAY 0.787234 (-3612 1862);
PAINT MONO (-3612 1862);
FORCEPROP 1 LASTPIN (-3600 2050) $PN 2
R 1
J 0
(-3612 2012);
DISPLAY 0.787234 (-3612 2012);
PAINT MONO (-3612 2012);
FORCEPROP 1 LAST PACK_TYPE 0402LF
J 0
(-3525 1800);
DISPLAY 0.723404 (-3525 1800);
PAINT SKYBLUE (-3525 1800);
FORCEPROP 1 LAST MATERIAL CHIP
J 0
(-3525 1950);
DISPLAY 0.787234 (-3525 1950);
PAINT SKYBLUE (-3525 1950);
FORCEPROP 1 LAST TOLERANCE 5%
J 0
(-3525 2000);
DISPLAY 0.723404 (-3525 2000);
PAINT SKYBLUE (-3525 2000);
FORCEPROP 1 LAST VALUE 0
R 2
J 0
(-3500 2075);
DISPLAY 0.723404 (-3500 2075);
PAINT SKYBLUE (-3500 2075);
FORCEPROP 1 LAST WATTAGE 1/16W
J 0
(-3525 1900);
DISPLAY 0.723404 (-3525 1900);
PAINT SKYBLUE (-3525 1900);
FORCEPROP 0 LAST ROOM HSC BOM1
J 0
(-3525 2150);
DISPLAY 0.680851 (-3525 2150);
FORCEPROP 2 LAST CDS_LIB pure_quanta
J 0
(-3600 1950);
DISPLAY INVISIBLE (-3600 1950);
FORCEPROP 1 LAST PATH I21
R 1
J 0
(-3750 1900);
DISPLAY 0.978723 (-3750 1900);
PAINT WHITE (-3750 1900);
DISPLAY INVISIBLE (-3750 1900);
FORCEPROP 1 LAST PART_NUMBER CS00002JB13
J 0
(-3525 1850);
DISPLAY 0.723404 (-3525 1850);
PAINT WHITE (-3525 1850);
DISPLAY INVISIBLE (-3525 1850);
FORCEADD OFFPAGE..4
R 2
(-2875 1350);
FORCEPROP 2 LAST $XR2 265 
J 0
(-3157 1314);
DISPLAY 0.638298 (-3157 1314);
PAINT MONO (-3157 1314);
FORCEPROP 2 LAST $XR1 264 
J 0
(-3277 1350);
DISPLAY 0.638298 (-3277 1350);
PAINT MONO (-3277 1350);
FORCEPROP 2 LAST $XR0 263 
J 0
(-3157 1350);
DISPLAY 0.638298 (-3157 1350);
PAINT MONO (-3157 1350);
FORCEPROP 2 LAST CDS_LIB standard
J 0
(-2875 1350);
DISPLAY INVISIBLE (-2875 1350);
FORCEPROP 1 LAST OFFPAGE TRUE
J 2
(-3200 1225);
DISPLAY 0.872340 (-3200 1225);
PAINT GREEN (-3200 1225);
DISPLAY INVISIBLE (-3200 1225);
FORCEPROP 1 LAST COMMENT_BODY TRUE
J 2
(-2850 1250);
DISPLAY 0.872340 (-2850 1250);
PAINT GREEN (-2850 1250);
DISPLAY INVISIBLE (-2850 1250);
FORCEPROP 2 LAST PATH I22
J 0
(-3150 1400);
DISPLAY 1.021277 (-3150 1400);
DISPLAY INVISIBLE (-3150 1400);
FORCEADD UNIVERSAL_GND..1
(-2700 525);
FORCEPROP 3 LASTPIN (-2700 575) SIG_NAME AGND_HSC\g
J 0
(-2690 585);
DISPLAY 0.659574 (-2690 585);
PAINT MONO (-2690 585);
DISPLAY INVISIBLE (-2690 585);
FORCEPROP 1 LAST HDL_POWER AGND_HSC
J 1
(-2675 450);
DISPLAY 0.723404 (-2675 450);
PAINT GREEN (-2675 450);
FORCEPROP 2 LAST CDS_LIB pure_quanta_power
J 0
(-2700 525);
DISPLAY INVISIBLE (-2700 525);
FORCEPROP 1 LAST PATH I23
J 0
(-2625 525);
DISPLAY 0.872340 (-2625 525);
PAINT AQUA (-2625 525);
DISPLAY INVISIBLE (-2625 525);
FORCEADD Q_CAP..1
(-2700 825);
FORCEPROP 1 LAST LOCATION PC2224
J 0
(-2625 925);
DISPLAY 0.723404 (-2625 925);
PAINT AQUA (-2625 925);
FORCEPROP 0 LAST $SEC 1
J 0
(-2625 975);
DISPLAY 0.680851 (-2625 975);
PAINT MONO (-2625 975);
DISPLAY INVISIBLE (-2625 975);
FORCEPROP 0 LAST CDS_SEC 1
J 0
(-2625 975);
DISPLAY 1.021277 (-2625 975);
DISPLAY INVISIBLE (-2625 975);
FORCEPROP 1 LASTPIN (-2700 925) $PN 1
J 0
(-2690 905);
DISPLAY 0.787234 (-2690 905);
PAINT MONO (-2690 905);
FORCEPROP 1 LASTPIN (-2700 725) $PN 2
J 0
(-2690 705);
DISPLAY 0.787234 (-2690 705);
PAINT MONO (-2690 705);
FORCEPROP 1 LAST PACK_TYPE 0402
J 0
(-2625 675);
DISPLAY 0.723404 (-2625 675);
PAINT SKYBLUE (-2625 675);
FORCEPROP 1 LAST VALUE 220PF
J 0
(-2625 875);
DISPLAY 0.723404 (-2625 875);
PAINT SKYBLUE (-2625 875);
FORCEPROP 0 LAST ROOM HSC BOM1
J 0
(-2625 975);
DISPLAY 0.680851 (-2625 975);
FORCEPROP 1 LAST VOLTAGE 50V
J 0
(-2625 825);
DISPLAY 0.723404 (-2625 825);
PAINT SKYBLUE (-2625 825);
FORCEPROP 1 LAST MATERIAL EMPTY
J 0
(-2625 775);
DISPLAY 0.723404 (-2625 775);
PAINT RED (-2625 775);
FORCEPROP 1 LAST TOLERANCE 10%
J 0
(-2650 775);
DISPLAY 0.978723 (-2650 775);
PAINT SKYBLUE (-2650 775);
DISPLAY INVISIBLE (-2650 775);
FORCEPROP 2 LAST CDS_LIB pure_quanta
J 0
(-2700 825);
DISPLAY INVISIBLE (-2700 825);
FORCEPROP 1 LAST PATH I24
J 0
(-2650 975);
DISPLAY 0.978723 (-2650 975);
PAINT WHITE (-2650 975);
DISPLAY INVISIBLE (-2650 975);
FORCEPROP 1 LAST PART_NUMBER TMP_QCH12206KB14
J 0
(-2625 725);
DISPLAY 0.723404 (-2625 725);
PAINT WHITE (-2625 725);
DISPLAY INVISIBLE (-2625 725);
FORCEADD UNIVERSAL_GND..1
(-2725 1575);
FORCEPROP 3 LASTPIN (-2725 1625) SIG_NAME AGND_HSC\g
J 0
(-2715 1635);
DISPLAY 0.659574 (-2715 1635);
PAINT MONO (-2715 1635);
DISPLAY INVISIBLE (-2715 1635);
FORCEPROP 1 LAST HDL_POWER AGND_HSC
J 1
(-2700 1500);
DISPLAY 0.723404 (-2700 1500);
PAINT GREEN (-2700 1500);
FORCEPROP 2 LAST CDS_LIB pure_quanta_power
J 0
(-2725 1575);
DISPLAY INVISIBLE (-2725 1575);
FORCEPROP 1 LAST PATH I25
J 0
(-2650 1575);
DISPLAY 0.872340 (-2650 1575);
PAINT AQUA (-2650 1575);
DISPLAY INVISIBLE (-2650 1575);
FORCEADD OFFPAGE..4
R 2
(-2050 1250);
FORCEPROP 2 LAST $XR2 265 
J 0
(-2542 1250);
DISPLAY 0.638298 (-2542 1250);
PAINT MONO (-2542 1250);
FORCEPROP 2 LAST $XR1 264 
J 0
(-2422 1250);
DISPLAY 0.638298 (-2422 1250);
PAINT MONO (-2422 1250);
FORCEPROP 2 LAST $XR0 263 
J 0
(-2302 1250);
DISPLAY 0.638298 (-2302 1250);
PAINT MONO (-2302 1250);
FORCEPROP 2 LAST CDS_LIB standard
J 0
(-2050 1250);
DISPLAY INVISIBLE (-2050 1250);
FORCEPROP 1 LAST OFFPAGE TRUE
J 2
(-2375 1125);
DISPLAY 0.872340 (-2375 1125);
PAINT GREEN (-2375 1125);
DISPLAY INVISIBLE (-2375 1125);
FORCEPROP 1 LAST COMMENT_BODY TRUE
J 2
(-2025 1150);
DISPLAY 0.872340 (-2025 1150);
PAINT GREEN (-2025 1150);
DISPLAY INVISIBLE (-2025 1150);
FORCEPROP 2 LAST PATH I26
J 0
(-2300 1300);
DISPLAY 1.021277 (-2300 1300);
DISPLAY INVISIBLE (-2300 1300);
FORCEADD OFFPAGE..4
R 2
(-2025 1475);
FORCEPROP 2 LAST $XR2 265 
J 0
(-2517 1475);
DISPLAY 0.638298 (-2517 1475);
PAINT MONO (-2517 1475);
FORCEPROP 2 LAST $XR1 264 
J 0
(-2397 1475);
DISPLAY 0.638298 (-2397 1475);
PAINT MONO (-2397 1475);
FORCEPROP 2 LAST $XR0 263 
J 0
(-2277 1475);
DISPLAY 0.638298 (-2277 1475);
PAINT MONO (-2277 1475);
FORCEPROP 2 LAST CDS_LIB standard
J 0
(-2025 1475);
DISPLAY INVISIBLE (-2025 1475);
FORCEPROP 1 LAST OFFPAGE TRUE
J 2
(-2350 1350);
DISPLAY 0.872340 (-2350 1350);
PAINT GREEN (-2350 1350);
DISPLAY INVISIBLE (-2350 1350);
FORCEPROP 1 LAST COMMENT_BODY TRUE
J 2
(-2000 1375);
DISPLAY 0.872340 (-2000 1375);
PAINT GREEN (-2000 1375);
DISPLAY INVISIBLE (-2000 1375);
FORCEPROP 2 LAST PATH I27
J 0
(-2275 1525);
DISPLAY 1.021277 (-2275 1525);
DISPLAY INVISIBLE (-2275 1525);
FORCEADD Q_RES..1
(-1900 1650);
FORCEPROP 1 LAST LOCATION PR3982
J 0
(-2175 1650);
DISPLAY 0.723404 (-2175 1650);
PAINT AQUA (-2175 1650);
FORCEPROP 0 LAST $SEC 1
J 0
(-1850 1725);
DISPLAY 0.680851 (-1850 1725);
PAINT MONO (-1850 1725);
DISPLAY INVISIBLE (-1850 1725);
FORCEPROP 0 LAST CDS_SEC 1
J 0
(-1850 1725);
DISPLAY 1.021277 (-1850 1725);
DISPLAY INVISIBLE (-1850 1725);
FORCEPROP 1 LASTPIN (-2000 1650) $PN 1
J 0
(-1988 1662);
DISPLAY 0.787234 (-1988 1662);
PAINT MONO (-1988 1662);
FORCEPROP 1 LASTPIN (-1800 1650) $PN 2
J 0
(-1838 1662);
DISPLAY 0.787234 (-1838 1662);
PAINT MONO (-1838 1662);
FORCEPROP 1 LAST PACK_TYPE 0402LF
J 0
(-1775 1575);
DISPLAY 0.723404 (-1775 1575);
PAINT SKYBLUE (-1775 1575);
FORCEPROP 1 LAST MATERIAL CHIP
J 0
(-1850 1525);
DISPLAY 0.723404 (-1850 1525);
PAINT SKYBLUE (-1850 1525);
FORCEPROP 1 LAST WATTAGE 1/16W
J 2
(-1875 1525);
DISPLAY 0.723404 (-1875 1525);
PAINT SKYBLUE (-1875 1525);
FORCEPROP 1 LAST VALUE 120K
J 2
(-1925 1575);
DISPLAY 0.723404 (-1925 1575);
PAINT SKYBLUE (-1925 1575);
FORCEPROP 1 LAST TOLERANCE 1%
J 0
(-1875 1575);
DISPLAY 0.723404 (-1875 1575);
PAINT SKYBLUE (-1875 1575);
FORCEPROP 0 LAST ROOM HSC BOM1
J 0
(-2300 1600);
DISPLAY 0.553191 (-2300 1600);
FORCEPROP 2 LAST CDS_LIB pure_quanta
J 0
(-1900 1650);
DISPLAY INVISIBLE (-1900 1650);
FORCEPROP 1 LAST PATH I28
J 0
(-1950 1800);
DISPLAY 0.978723 (-1950 1800);
PAINT WHITE (-1950 1800);
DISPLAY INVISIBLE (-1950 1800);
FORCEPROP 1 LAST PART_NUMBER CS41202FB05
J 0
(-1750 1650);
DISPLAY 0.723404 (-1750 1650);
PAINT WHITE (-1750 1650);
DISPLAY INVISIBLE (-1750 1650);
FORCEADD UNIVERSAL_POWER..1
(-3600 2200);
FORCEPROP 3 LASTPIN (-3600 2150) SIG_NAME HSC_VDD\g
J 0
(-3590 2160);
DISPLAY 0.659574 (-3590 2160);
PAINT MONO (-3590 2160);
DISPLAY INVISIBLE (-3590 2160);
FORCEPROP 1 LAST HDL_POWER HSC_VDD
J 1
(-3600 2250);
DISPLAY 0.723404 (-3600 2250);
PAINT GREEN (-3600 2250);
FORCEPROP 2 LAST CDS_LIB pure_quanta_power
J 0
(-3600 2200);
DISPLAY INVISIBLE (-3600 2200);
FORCEPROP 2 LAST BOM_COST MIO_VRD_SB
J 0
(-3600 2300);
DISPLAY 0.617021 (-3600 2300);
PAINT PURPLE (-3600 2300);
DISPLAY INVISIBLE (-3600 2300);
FORCEPROP 1 LAST PATH I29
J 0
(-3550 2225);
DISPLAY 0.872340 (-3550 2225);
PAINT AQUA (-3550 2225);
DISPLAY INVISIBLE (-3550 2225);
FORCEADD UNIVERSAL_GND..1
(-3575 -1600);
FORCEPROP 3 LASTPIN (-3575 -1550) SIG_NAME AGND_HSC\g
J 0
(-3565 -1540);
DISPLAY 0.659574 (-3565 -1540);
PAINT MONO (-3565 -1540);
DISPLAY INVISIBLE (-3565 -1540);
FORCEPROP 1 LAST HDL_POWER AGND_HSC
J 1
(-3550 -1675);
DISPLAY 0.723404 (-3550 -1675);
PAINT GREEN (-3550 -1675);
FORCEPROP 2 LAST CDS_LIB pure_quanta_power
J 0
(-3575 -1600);
DISPLAY INVISIBLE (-3575 -1600);
FORCEPROP 1 LAST PATH I3
J 0
(-3500 -1600);
DISPLAY 0.872340 (-3500 -1600);
PAINT AQUA (-3500 -1600);
DISPLAY INVISIBLE (-3500 -1600);
FORCEADD Q_CAP..1
(-1950 825);
FORCEPROP 1 LAST LOCATION PC2350
J 0
(-1875 925);
DISPLAY 0.808511 (-1875 925);
PAINT AQUA (-1875 925);
FORCEPROP 0 LAST $SEC 1
J 0
(-1875 975);
DISPLAY 0.680851 (-1875 975);
PAINT MONO (-1875 975);
DISPLAY INVISIBLE (-1875 975);
FORCEPROP 0 LAST CDS_SEC 1
J 0
(-1875 975);
DISPLAY 1.021277 (-1875 975);
DISPLAY INVISIBLE (-1875 975);
FORCEPROP 1 LASTPIN (-1950 925) $PN 1
J 0
(-1940 905);
DISPLAY 0.787234 (-1940 905);
PAINT MONO (-1940 905);
FORCEPROP 1 LASTPIN (-1950 725) $PN 2
J 0
(-1940 705);
DISPLAY 0.787234 (-1940 705);
PAINT MONO (-1940 705);
FORCEPROP 1 LAST VALUE 1NF
J 0
(-1875 875);
DISPLAY 0.723404 (-1875 875);
PAINT SKYBLUE (-1875 875);
FORCEPROP 1 LAST VOLTAGE 50V
J 0
(-1875 825);
DISPLAY 0.723404 (-1875 825);
PAINT SKYBLUE (-1875 825);
FORCEPROP 1 LAST MATERIAL EMPTY
J 0
(-1875 775);
DISPLAY 0.723404 (-1875 775);
PAINT RED (-1875 775);
FORCEPROP 1 LAST PACK_TYPE 0402
J 0
(-1875 675);
DISPLAY 0.723404 (-1875 675);
PAINT SKYBLUE (-1875 675);
FORCEPROP 0 LAST ROOM HSC BOM1
J 0
(-1875 975);
DISPLAY 0.680851 (-1875 975);
FORCEPROP 2 LAST CDS_LIB pure_quanta
J 0
(-1950 825);
DISPLAY INVISIBLE (-1950 825);
FORCEPROP 1 LAST TOLERANCE 10%
J 0
(-1900 775);
DISPLAY 0.978723 (-1900 775);
PAINT SKYBLUE (-1900 775);
DISPLAY INVISIBLE (-1900 775);
FORCEPROP 1 LAST PATH I30
J 0
(-1900 975);
DISPLAY 0.978723 (-1900 975);
PAINT WHITE (-1900 975);
DISPLAY INVISIBLE (-1900 975);
FORCEPROP 1 LAST PART_NUMBER CH21006KB16
J 0
(-1875 725);
DISPLAY 0.723404 (-1875 725);
PAINT WHITE (-1875 725);
DISPLAY INVISIBLE (-1875 725);
FORCEADD Q_RES..2
(-1475 825);
FORCEPROP 1 LAST LOCATION PR3986
J 0
(-1420 975);
DISPLAY 0.723404 (-1420 975);
PAINT AQUA (-1420 975);
FORCEPROP 0 LAST $SEC 1
J 0
(-1400 1025);
DISPLAY 0.680851 (-1400 1025);
PAINT MONO (-1400 1025);
DISPLAY INVISIBLE (-1400 1025);
FORCEPROP 0 LAST CDS_SEC 1
J 0
(-1400 1025);
DISPLAY 1.021277 (-1400 1025);
DISPLAY INVISIBLE (-1400 1025);
FORCEPROP 1 LASTPIN (-1475 925) $PN 1
J 0
(-1470 887);
DISPLAY 0.787234 (-1470 887);
PAINT MONO (-1470 887);
FORCEPROP 1 LASTPIN (-1475 725) $PN 2
J 0
(-1470 735);
DISPLAY 0.787234 (-1470 735);
PAINT MONO (-1470 735);
FORCEPROP 1 LAST VALUE 2K
J 0
(-1420 925);
DISPLAY 0.723404 (-1420 925);
PAINT SKYBLUE (-1420 925);
FORCEPROP 1 LAST MATERIAL CHIP
J 0
(-1425 775);
DISPLAY 0.723404 (-1425 775);
PAINT SKYBLUE (-1425 775);
FORCEPROP 1 LAST TOLERANCE 0.1%
J 0
(-1420 875);
DISPLAY 0.723404 (-1420 875);
PAINT SKYBLUE (-1420 875);
FORCEPROP 1 LAST WATTAGE 1/16W
J 0
(-1425 825);
DISPLAY 0.723404 (-1425 825);
PAINT SKYBLUE (-1425 825);
FORCEPROP 1 LAST PACK_TYPE 0402LF
J 0
(-1425 675);
DISPLAY 0.723404 (-1425 675);
PAINT SKYBLUE (-1425 675);
FORCEPROP 0 LAST ROOM HSC BOM1
J 0
(-1450 600);
DISPLAY 0.680851 (-1450 600);
FORCEPROP 2 LAST CDS_LIB pure_quanta
J 0
(-1475 825);
DISPLAY INVISIBLE (-1475 825);
FORCEPROP 1 LAST PATH I31
J 0
(-1425 1000);
DISPLAY 0.978723 (-1425 1000);
PAINT WHITE (-1425 1000);
DISPLAY INVISIBLE (-1425 1000);
FORCEPROP 1 LAST PART_NUMBER CS22002BB07
J 0
(-1425 725);
DISPLAY 0.723404 (-1425 725);
PAINT WHITE (-1425 725);
DISPLAY INVISIBLE (-1425 725);
FORCEADD OFFPAGE..5
(-1050 1050);
FORCEPROP 2 LAST $XR2 263 
J 0
(-1305 1014);
DISPLAY 0.638298 (-1305 1014);
PAINT MONO (-1305 1014);
FORCEPROP 2 LAST $XR1 265 
J 0
(-1425 1050);
DISPLAY 0.638298 (-1425 1050);
PAINT MONO (-1425 1050);
FORCEPROP 2 LAST $XR0 264 
J 0
(-1305 1050);
DISPLAY 0.638298 (-1305 1050);
PAINT MONO (-1305 1050);
FORCEPROP 2 LAST CDS_LIB standard
J 0
(-1050 1050);
DISPLAY INVISIBLE (-1050 1050);
FORCEPROP 1 LAST OFFPAGE TRUE
J 0
(-725 925);
DISPLAY 0.872340 (-725 925);
PAINT AQUA (-725 925);
DISPLAY INVISIBLE (-725 925);
FORCEPROP 1 LAST COMMENT_BODY TRUE
J 0
(-950 975);
DISPLAY 1.170213 (-950 975);
PAINT GREEN (-950 975);
DISPLAY INVISIBLE (-950 975);
FORCEPROP 2 LAST PATH I32
J 0
(-1300 1100);
DISPLAY 1.021277 (-1300 1100);
DISPLAY INVISIBLE (-1300 1100);
FORCEADD Q_RES..1
(-1325 1475);
FORCEPROP 1 LAST LOCATION PR3988
J 0
(-1625 1475);
DISPLAY 0.723404 (-1625 1475);
PAINT AQUA (-1625 1475);
FORCEPROP 0 LAST $SEC 1
J 0
(-1200 1550);
DISPLAY 0.680851 (-1200 1550);
PAINT MONO (-1200 1550);
DISPLAY INVISIBLE (-1200 1550);
FORCEPROP 0 LAST CDS_SEC 1
J 0
(-1200 1550);
DISPLAY 1.021277 (-1200 1550);
DISPLAY INVISIBLE (-1200 1550);
FORCEPROP 1 LASTPIN (-1425 1475) $PN 1
J 0
(-1413 1487);
DISPLAY 0.787234 (-1413 1487);
PAINT MONO (-1413 1487);
FORCEPROP 1 LASTPIN (-1225 1475) $PN 2
J 0
(-1263 1487);
DISPLAY 0.787234 (-1263 1487);
PAINT MONO (-1263 1487);
FORCEPROP 0 LAST ROOM HSC BOM1
J 0
(-1450 1550);
DISPLAY 0.553191 (-1450 1550);
FORCEPROP 1 LAST VALUE 0
J 2
(-1150 1500);
DISPLAY 0.723404 (-1150 1500);
PAINT SKYBLUE (-1150 1500);
FORCEPROP 1 LAST TOLERANCE 5%
J 0
(-1200 1425);
DISPLAY 0.723404 (-1200 1425);
PAINT SKYBLUE (-1200 1425);
FORCEPROP 1 LAST MATERIAL CHIP
J 0
(-1150 1375);
DISPLAY 0.723404 (-1150 1375);
PAINT SKYBLUE (-1150 1375);
FORCEPROP 1 LAST PACK_TYPE 0402LF
J 0
(-1400 1375);
DISPLAY 0.723404 (-1400 1375);
PAINT SKYBLUE (-1400 1375);
FORCEPROP 1 LAST WATTAGE 1/16W
J 2
(-1450 1375);
DISPLAY 0.723404 (-1450 1375);
PAINT SKYBLUE (-1450 1375);
FORCEPROP 2 LAST CDS_LIB pure_quanta
J 0
(-1325 1475);
DISPLAY INVISIBLE (-1325 1475);
FORCEPROP 1 LAST PATH I33
J 0
(-1375 1625);
DISPLAY 0.978723 (-1375 1625);
PAINT WHITE (-1375 1625);
DISPLAY INVISIBLE (-1375 1625);
FORCEPROP 1 LAST PART_NUMBER CS00002JB13
J 0
(-1650 1425);
DISPLAY 0.723404 (-1650 1425);
PAINT WHITE (-1650 1425);
DISPLAY INVISIBLE (-1650 1425);
FORCEADD Q_RES..2
(-950 825);
FORCEPROP 1 LAST LOCATION PR3990
J 0
(-895 975);
DISPLAY 0.723404 (-895 975);
PAINT AQUA (-895 975);
FORCEPROP 0 LAST $SEC 1
J 0
(-875 1025);
DISPLAY 0.680851 (-875 1025);
PAINT MONO (-875 1025);
DISPLAY INVISIBLE (-875 1025);
FORCEPROP 0 LAST CDS_SEC 1
J 0
(-875 1025);
DISPLAY 1.021277 (-875 1025);
DISPLAY INVISIBLE (-875 1025);
FORCEPROP 1 LASTPIN (-950 925) $PN 1
J 0
(-945 887);
DISPLAY 0.787234 (-945 887);
PAINT MONO (-945 887);
FORCEPROP 1 LASTPIN (-950 725) $PN 2
J 0
(-945 735);
DISPLAY 0.787234 (-945 735);
PAINT MONO (-945 735);
FORCEPROP 1 LAST TOLERANCE 0.1%
J 0
(-895 875);
DISPLAY 0.723404 (-895 875);
PAINT SKYBLUE (-895 875);
FORCEPROP 1 LAST MATERIAL CHIP
J 0
(-900 775);
DISPLAY 0.723404 (-900 775);
PAINT SKYBLUE (-900 775);
FORCEPROP 1 LAST VALUE 2K
J 0
(-895 925);
DISPLAY 0.723404 (-895 925);
PAINT SKYBLUE (-895 925);
FORCEPROP 1 LAST WATTAGE 1/16W
J 0
(-900 825);
DISPLAY 0.723404 (-900 825);
PAINT SKYBLUE (-900 825);
FORCEPROP 1 LAST PACK_TYPE 0402LF
J 0
(-900 675);
DISPLAY 0.723404 (-900 675);
PAINT SKYBLUE (-900 675);
FORCEPROP 0 LAST ROOM HSC BOM1
J 0
(-900 600);
DISPLAY 0.680851 (-900 600);
FORCEPROP 2 LAST CDS_LIB pure_quanta
J 0
(-950 825);
DISPLAY INVISIBLE (-950 825);
FORCEPROP 1 LAST PATH I34
J 0
(-900 1000);
DISPLAY 0.978723 (-900 1000);
PAINT WHITE (-900 1000);
DISPLAY INVISIBLE (-900 1000);
FORCEPROP 1 LAST PART_NUMBER CS22002BB07
J 0
(-900 725);
DISPLAY 0.723404 (-900 725);
PAINT WHITE (-900 725);
DISPLAY INVISIBLE (-900 725);
FORCEADD MP5991GLUZ..1
(25 1575);
FORCEPROP 1 LAST LOCATION PU296
J 0
(-300 2575);
DISPLAY 1.148936 (-300 2575);
PAINT GREEN (-300 2575);
FORCEPROP 2 LAST SEC 1
J 0
(-275 2800);
DISPLAY 0.680851 (-275 2800);
PAINT MONO (-275 2800);
DISPLAY INVISIBLE (-275 2800);
FORCEPROP 2 LASTPIN (-450 1150) $PN 23
J 2
(-460 1160);
DISPLAY 0.680851 (-460 1160);
PAINT MONO (-460 1160);
FORCEPROP 2 LASTPIN (500 1500) $PN 3
J 0
(510 1510);
DISPLAY 0.680851 (510 1510);
PAINT MONO (510 1510);
FORCEPROP 2 LASTPIN (500 1400) $PN 6
J 0
(510 1410);
DISPLAY 0.680851 (510 1410);
PAINT MONO (510 1410);
FORCEPROP 2 LASTPIN (-450 850) $PN 20
J 2
(-460 860);
DISPLAY 0.680851 (-460 860);
PAINT MONO (-460 860);
FORCEPROP 2 LASTPIN (500 1200) $PN 5
J 0
(510 1210);
DISPLAY 0.680851 (510 1210);
PAINT MONO (510 1210);
FORCEPROP 2 LASTPIN (-450 1050) $PN 22
J 2
(-460 1060);
DISPLAY 0.680851 (-460 1060);
PAINT MONO (-460 1060);
FORCEPROP 2 LASTPIN (-450 1650) $PN 8
J 2
(-460 1660);
DISPLAY 0.680851 (-460 1660);
PAINT MONO (-460 1660);
FORCEPROP 2 LASTPIN (500 1300) $PN 7
J 0
(510 1310);
DISPLAY 0.680851 (510 1310);
PAINT MONO (510 1310);
FORCEPROP 2 LASTPIN (-450 1250) $PN 24
J 2
(-460 1260);
DISPLAY 0.680851 (-460 1260);
PAINT MONO (-460 1260);
FORCEPROP 2 LASTPIN (-450 1350) $PN 4
J 2
(-460 1360);
DISPLAY 0.680851 (-460 1360);
PAINT MONO (-460 1360);
FORCEPROP 2 LASTPIN (-450 1550) $PN 17
J 2
(-460 1560);
DISPLAY 0.680851 (-460 1560);
PAINT MONO (-460 1560);
FORCEPROP 2 LASTPIN (500 1000) $PN 19
J 0
(510 1010);
DISPLAY 0.680851 (510 1010);
PAINT MONO (510 1010);
FORCEPROP 2 LASTPIN (-450 1750) $PN 21
J 2
(-460 1760);
DISPLAY 0.680851 (-460 1760);
PAINT MONO (-460 1760);
FORCEPROP 2 LASTPIN (-450 2300) $PN 9
J 2
(-460 2310);
DISPLAY 0.680851 (-460 2310);
PAINT MONO (-460 2310);
FORCEPROP 2 LASTPIN (-450 2250) $PN 10
J 2
(-460 2260);
DISPLAY 0.680851 (-460 2260);
PAINT MONO (-460 2260);
FORCEPROP 2 LASTPIN (-450 2200) $PN 11
J 2
(-460 2210);
DISPLAY 0.680851 (-460 2210);
PAINT MONO (-460 2210);
FORCEPROP 2 LASTPIN (-450 2150) $PN 12
J 2
(-460 2160);
DISPLAY 0.680851 (-460 2160);
PAINT MONO (-460 2160);
FORCEPROP 2 LASTPIN (-450 2100) $PN 13
J 2
(-460 2110);
DISPLAY 0.680851 (-460 2110);
PAINT MONO (-460 2110);
FORCEPROP 2 LASTPIN (-450 2050) $PN 14
J 2
(-460 2060);
DISPLAY 0.680851 (-460 2060);
PAINT MONO (-460 2060);
FORCEPROP 2 LASTPIN (-450 2000) $PN 15
J 2
(-460 2010);
DISPLAY 0.680851 (-460 2010);
PAINT MONO (-460 2010);
FORCEPROP 2 LASTPIN (-450 1950) $PN 16
J 2
(-460 1960);
DISPLAY 0.680851 (-460 1960);
PAINT MONO (-460 1960);
FORCEPROP 2 LASTPIN (-450 1900) $PN 33
J 2
(-460 1910);
DISPLAY 0.680851 (-460 1910);
PAINT MONO (-460 1910);
FORCEPROP 2 LASTPIN (500 2300) $PN 1
J 0
(510 2310);
DISPLAY 0.680851 (510 2310);
PAINT MONO (510 2310);
FORCEPROP 2 LASTPIN (500 2250) $PN 2
J 0
(510 2260);
DISPLAY 0.680851 (510 2260);
PAINT MONO (510 2260);
FORCEPROP 2 LASTPIN (500 2200) $PN 25
J 0
(510 2210);
DISPLAY 0.680851 (510 2210);
PAINT MONO (510 2210);
FORCEPROP 2 LASTPIN (500 2150) $PN 26
J 0
(510 2160);
DISPLAY 0.680851 (510 2160);
PAINT MONO (510 2160);
FORCEPROP 2 LASTPIN (500 2100) $PN 27
J 0
(510 2110);
DISPLAY 0.680851 (510 2110);
PAINT MONO (510 2110);
FORCEPROP 2 LASTPIN (500 2050) $PN 28
J 0
(510 2060);
DISPLAY 0.680851 (510 2060);
PAINT MONO (510 2060);
FORCEPROP 2 LASTPIN (500 2000) $PN 29
J 0
(510 2010);
DISPLAY 0.680851 (510 2010);
PAINT MONO (510 2010);
FORCEPROP 2 LASTPIN (500 1950) $PN 30
J 0
(510 1960);
DISPLAY 0.680851 (510 1960);
PAINT MONO (510 1960);
FORCEPROP 2 LASTPIN (500 1900) $PN 31
J 0
(510 1910);
DISPLAY 0.680851 (510 1910);
PAINT MONO (510 1910);
FORCEPROP 2 LASTPIN (500 1850) $PN 32
J 0
(510 1860);
DISPLAY 0.680851 (510 1860);
PAINT MONO (510 1860);
FORCEPROP 2 LASTPIN (500 1100) $PN 18
J 0
(510 1110);
DISPLAY 0.680851 (510 1110);
PAINT MONO (510 1110);
FORCEPROP 0 LAST ROOM HSC BOM1
J 0
(-300 2700);
DISPLAY 0.680851 (-300 2700);
FORCEPROP 1 LAST MATERIAL IC
J 0
(-300 2382);
DISPLAY 0.723404 (-300 2382);
PAINT GREEN (-300 2382);
FORCEPROP 2 LAST PART_TYPE SMLF
J 0
(-300 2525);
DISPLAY 1.021277 (-300 2525);
FORCEPROP 2 LAST VALUE MP5991GLU-Z
J 0
(-300 2475);
DISPLAY 1.021277 (-300 2475);
FORCEPROP 2 LAST SEC_TYPE 
J 0
(-275 2800);
DISPLAY 1.021277 (-275 2800);
DISPLAY INVISIBLE (-275 2800);
FORCEPROP 1 LAST NEEDS_NO_SIZE TRUE
J 0
(25 1575);
DISPLAY 0.723404 (25 1575);
PAINT GREEN (25 1575);
DISPLAY INVISIBLE (25 1575);
FORCEPROP 1 LAST CDS_LMAN_SYM_OUTLINE -325,775,325,-775
J 0
(25 1575);
DISPLAY 0.468085 (25 1575);
PAINT GREEN (25 1575);
DISPLAY INVISIBLE (25 1575);
FORCEPROP 2 LAST CDS_LIB pure_quanta
J 0
(25 1575);
DISPLAY INVISIBLE (25 1575);
FORCEPROP 1 LAST PATH I35
J 0
(25 1575);
DISPLAY 0.723404 (25 1575);
PAINT GREEN (25 1575);
DISPLAY INVISIBLE (25 1575);
FORCEPROP 1 LAST PART_NUMBER AL005991A00
J 0
(-300 2425);
DISPLAY 0.723404 (-300 2425);
PAINT GREEN (-300 2425);
DISPLAY INVISIBLE (-300 2425);
FORCEADD UNIVERSAL_POWER..1
(-950 2450);
FORCEPROP 3 LASTPIN (-950 2400) SIG_NAME P12V_PSU\g
J 0
(-940 2410);
DISPLAY 0.659574 (-940 2410);
PAINT MONO (-940 2410);
DISPLAY INVISIBLE (-940 2410);
FORCEPROP 1 LAST HDL_POWER P12V_PSU
J 1
(-950 2500);
DISPLAY 0.723404 (-950 2500);
PAINT GREEN (-950 2500);
FORCEPROP 2 LAST BOM_COST MIO_VRD_SB
J 0
(-950 2550);
DISPLAY 0.617021 (-950 2550);
PAINT PURPLE (-950 2550);
DISPLAY INVISIBLE (-950 2550);
FORCEPROP 2 LAST CDS_LIB pure_quanta_power
J 0
(-950 2450);
DISPLAY INVISIBLE (-950 2450);
FORCEPROP 1 LAST PATH I36
J 0
(-900 2475);
DISPLAY 0.872340 (-900 2475);
PAINT AQUA (-900 2475);
DISPLAY INVISIBLE (-900 2475);
FORCEADD UNIVERSAL_GND..1
(1000 -2150);
FORCEPROP 3 LASTPIN (1000 -2100) SIG_NAME AGND_HSC\g
J 0
(1010 -2090);
DISPLAY 0.659574 (1010 -2090);
PAINT MONO (1010 -2090);
DISPLAY INVISIBLE (1010 -2090);
FORCEPROP 1 LAST HDL_POWER AGND_HSC
J 1
(1025 -2225);
DISPLAY 0.723404 (1025 -2225);
PAINT GREEN (1025 -2225);
FORCEPROP 2 LAST CDS_LIB pure_quanta_power
J 0
(1000 -2150);
DISPLAY INVISIBLE (1000 -2150);
FORCEPROP 1 LAST PATH I37
J 0
(1075 -2150);
DISPLAY 0.872340 (1075 -2150);
PAINT AQUA (1075 -2150);
DISPLAY INVISIBLE (1075 -2150);
FORCEADD Q_CAP..1
(1000 -1925);
FORCEPROP 1 LAST LOCATION PC2227
J 0
(1050 -1850);
DISPLAY 0.723404 (1050 -1850);
PAINT AQUA (1050 -1850);
FORCEPROP 0 LAST $SEC 1
J 0
(1050 -1800);
DISPLAY 0.680851 (1050 -1800);
PAINT MONO (1050 -1800);
DISPLAY INVISIBLE (1050 -1800);
FORCEPROP 0 LAST CDS_SEC 1
J 0
(1050 -1800);
DISPLAY 1.021277 (1050 -1800);
DISPLAY INVISIBLE (1050 -1800);
FORCEPROP 1 LASTPIN (1000 -1825) $PN 1
J 0
(1010 -1845);
DISPLAY 0.787234 (1010 -1845);
PAINT MONO (1010 -1845);
FORCEPROP 1 LASTPIN (1000 -2025) $PN 2
J 0
(1010 -2045);
DISPLAY 0.787234 (1010 -2045);
PAINT MONO (1010 -2045);
FORCEPROP 1 LAST VALUE 0.068UF
J 0
(1050 -1900);
DISPLAY 0.723404 (1050 -1900);
PAINT SKYBLUE (1050 -1900);
FORCEPROP 1 LAST VOLTAGE 16V
J 0
(1050 -1950);
DISPLAY 0.723404 (1050 -1950);
PAINT SKYBLUE (1050 -1950);
FORCEPROP 0 LAST ROOM HSC BOM1
J 0
(725 -2000);
DISPLAY 0.680851 (725 -2000);
FORCEPROP 1 LAST MATERIAL X7R
J 0
(1050 -2000);
DISPLAY 0.723404 (1050 -2000);
PAINT SKYBLUE (1050 -2000);
FORCEPROP 1 LAST PACK_TYPE 0402
J 0
(1050 -2100);
DISPLAY 0.723404 (1050 -2100);
PAINT SKYBLUE (1050 -2100);
FORCEPROP 2 LAST CDS_LIB pure_quanta
J 0
(1000 -1925);
DISPLAY INVISIBLE (1000 -1925);
FORCEPROP 1 LAST TOLERANCE 10%
J 0
(1050 -1975);
DISPLAY 0.978723 (1050 -1975);
PAINT SKYBLUE (1050 -1975);
DISPLAY INVISIBLE (1050 -1975);
FORCEPROP 1 LAST PATH I38
J 0
(1050 -1775);
DISPLAY 0.978723 (1050 -1775);
PAINT WHITE (1050 -1775);
DISPLAY INVISIBLE (1050 -1775);
FORCEPROP 1 LAST PART_NUMBER CH3683K1B09
J 0
(1050 -2050);
DISPLAY 0.723404 (1050 -2050);
PAINT WHITE (1050 -2050);
DISPLAY INVISIBLE (1050 -2050);
FORCEADD Q_RES..1
(1500 -1375);
FORCEPROP 1 LAST LOCATION PR3995
J 0
(1200 -1375);
DISPLAY 0.723404 (1200 -1375);
PAINT AQUA (1200 -1375);
FORCEPROP 0 LAST $SEC 1
J 0
(1650 -1300);
DISPLAY 0.680851 (1650 -1300);
PAINT MONO (1650 -1300);
DISPLAY INVISIBLE (1650 -1300);
FORCEPROP 0 LAST CDS_SEC 1
J 0
(1650 -1300);
DISPLAY 1.021277 (1650 -1300);
DISPLAY INVISIBLE (1650 -1300);
FORCEPROP 1 LASTPIN (1400 -1375) $PN 1
J 0
(1412 -1363);
DISPLAY 0.787234 (1412 -1363);
PAINT MONO (1412 -1363);
FORCEPROP 1 LASTPIN (1600 -1375) $PN 2
J 0
(1562 -1363);
DISPLAY 0.787234 (1562 -1363);
PAINT MONO (1562 -1363);
FORCEPROP 0 LAST ROOM HSC BOM1
J 0
(1400 -1525);
DISPLAY 0.553191 (1400 -1525);
FORCEPROP 1 LAST PACK_TYPE 0402LF
J 0
(1425 -1475);
DISPLAY 0.723404 (1425 -1475);
PAINT SKYBLUE (1425 -1475);
FORCEPROP 1 LAST WATTAGE 1/16W
J 2
(1375 -1475);
DISPLAY 0.723404 (1375 -1475);
PAINT SKYBLUE (1375 -1475);
FORCEPROP 1 LAST MATERIAL CHIP
J 0
(1675 -1475);
DISPLAY 0.723404 (1675 -1475);
PAINT SKYBLUE (1675 -1475);
FORCEPROP 1 LAST VALUE 0
J 2
(1650 -1350);
DISPLAY 0.723404 (1650 -1350);
PAINT SKYBLUE (1650 -1350);
FORCEPROP 1 LAST TOLERANCE 5%
J 0
(1625 -1425);
DISPLAY 0.723404 (1625 -1425);
PAINT SKYBLUE (1625 -1425);
FORCEPROP 2 LAST CDS_LIB pure_quanta
J 0
(1500 -1375);
DISPLAY INVISIBLE (1500 -1375);
FORCEPROP 1 LAST PATH I39
J 0
(1450 -1225);
DISPLAY 0.978723 (1450 -1225);
PAINT WHITE (1450 -1225);
DISPLAY INVISIBLE (1450 -1225);
FORCEPROP 1 LAST PART_NUMBER CS00002JB13
J 0
(1175 -1425);
DISPLAY 0.723404 (1175 -1425);
PAINT WHITE (1175 -1425);
DISPLAY INVISIBLE (1175 -1425);
FORCEADD Q_CAP..1
(-3575 -1300);
FORCEPROP 1 LAST LOCATION PC2223
J 0
(-3500 -1150);
DISPLAY 0.723404 (-3500 -1150);
PAINT AQUA (-3500 -1150);
FORCEPROP 0 LAST $SEC 1
J 0
(-3500 -1100);
DISPLAY 0.680851 (-3500 -1100);
PAINT MONO (-3500 -1100);
DISPLAY INVISIBLE (-3500 -1100);
FORCEPROP 0 LAST CDS_SEC 1
J 0
(-3500 -1100);
DISPLAY 1.021277 (-3500 -1100);
DISPLAY INVISIBLE (-3500 -1100);
FORCEPROP 1 LASTPIN (-3575 -1200) $PN 1
J 0
(-3565 -1220);
DISPLAY 0.787234 (-3565 -1220);
PAINT MONO (-3565 -1220);
FORCEPROP 1 LASTPIN (-3575 -1400) $PN 2
J 0
(-3565 -1420);
DISPLAY 0.787234 (-3565 -1420);
PAINT MONO (-3565 -1420);
FORCEPROP 1 LAST VALUE 1UF
J 0
(-3500 -1200);
DISPLAY 0.723404 (-3500 -1200);
PAINT SKYBLUE (-3500 -1200);
FORCEPROP 1 LAST VOLTAGE 25V
J 0
(-3500 -1250);
DISPLAY 0.723404 (-3500 -1250);
PAINT SKYBLUE (-3500 -1250);
FORCEPROP 1 LAST MATERIAL X6S
J 0
(-3500 -1300);
DISPLAY 0.723404 (-3500 -1300);
PAINT SKYBLUE (-3500 -1300);
FORCEPROP 0 LAST ROOM HSC BOM1
J 0
(-3500 -1100);
DISPLAY 0.680851 (-3500 -1100);
FORCEPROP 1 LAST PACK_TYPE C0402
J 0
(-3500 -1400);
DISPLAY 0.723404 (-3500 -1400);
PAINT SKYBLUE (-3500 -1400);
FORCEPROP 1 LAST TOLERANCE 10%
J 0
(-3525 -1350);
DISPLAY 0.978723 (-3525 -1350);
PAINT SKYBLUE (-3525 -1350);
DISPLAY INVISIBLE (-3525 -1350);
FORCEPROP 2 LAST CDS_LIB pure_quanta
J 0
(-3575 -1300);
DISPLAY INVISIBLE (-3575 -1300);
FORCEPROP 1 LAST PATH I4
J 0
(-3525 -1150);
DISPLAY 0.978723 (-3525 -1150);
PAINT WHITE (-3525 -1150);
DISPLAY INVISIBLE (-3525 -1150);
FORCEPROP 1 LAST PART_NUMBER CH5104KEB02
J 0
(-3500 -1350);
DISPLAY 0.723404 (-3500 -1350);
PAINT WHITE (-3500 -1350);
DISPLAY INVISIBLE (-3500 -1350);
FORCEADD Q_RES..1
(1500 -1200);
FORCEPROP 1 LAST LOCATION PR3994
J 0
(1200 -1200);
DISPLAY 0.723404 (1200 -1200);
PAINT AQUA (1200 -1200);
FORCEPROP 0 LAST $SEC 1
J 0
(1650 -1125);
DISPLAY 0.680851 (1650 -1125);
PAINT MONO (1650 -1125);
DISPLAY INVISIBLE (1650 -1125);
FORCEPROP 0 LAST CDS_SEC 1
J 0
(1650 -1125);
DISPLAY 1.021277 (1650 -1125);
DISPLAY INVISIBLE (1650 -1125);
FORCEPROP 1 LASTPIN (1400 -1200) $PN 1
J 0
(1412 -1188);
DISPLAY 0.787234 (1412 -1188);
PAINT MONO (1412 -1188);
FORCEPROP 1 LASTPIN (1600 -1200) $PN 2
J 0
(1562 -1188);
DISPLAY 0.787234 (1562 -1188);
PAINT MONO (1562 -1188);
FORCEPROP 1 LAST MATERIAL CHIP
J 0
(1675 -1300);
DISPLAY 0.723404 (1675 -1300);
PAINT SKYBLUE (1675 -1300);
FORCEPROP 1 LAST PACK_TYPE 0402LF
J 0
(1425 -1300);
DISPLAY 0.723404 (1425 -1300);
PAINT SKYBLUE (1425 -1300);
FORCEPROP 1 LAST WATTAGE 1/16W
J 2
(1375 -1300);
DISPLAY 0.723404 (1375 -1300);
PAINT SKYBLUE (1375 -1300);
FORCEPROP 1 LAST TOLERANCE 5%
J 0
(1625 -1250);
DISPLAY 0.723404 (1625 -1250);
PAINT SKYBLUE (1625 -1250);
FORCEPROP 0 LAST ROOM HSC BOM1
J 0
(1400 -1125);
DISPLAY 0.553191 (1400 -1125);
FORCEPROP 1 LAST VALUE 0
J 2
(1650 -1175);
DISPLAY 0.723404 (1650 -1175);
PAINT SKYBLUE (1650 -1175);
FORCEPROP 2 LAST CDS_LIB pure_quanta
J 0
(1500 -1200);
DISPLAY INVISIBLE (1500 -1200);
FORCEPROP 1 LAST PATH I40
J 0
(1450 -1050);
DISPLAY 0.978723 (1450 -1050);
PAINT WHITE (1450 -1050);
DISPLAY INVISIBLE (1450 -1050);
FORCEPROP 1 LAST PART_NUMBER CS00002JB13
J 0
(1175 -1250);
DISPLAY 0.723404 (1175 -1250);
PAINT WHITE (1175 -1250);
DISPLAY INVISIBLE (1175 -1250);
FORCEADD UNIVERSAL_POWER..1
(1125 -325);
FORCEPROP 3 LASTPIN (1125 -375) SIG_NAME P12V_AUX\g
J 0
(1135 -365);
DISPLAY 0.659574 (1135 -365);
PAINT MONO (1135 -365);
DISPLAY INVISIBLE (1135 -365);
FORCEPROP 1 LAST HDL_POWER P12V_AUX
J 1
(1125 -275);
DISPLAY 0.723404 (1125 -275);
PAINT GREEN (1125 -275);
FORCEPROP 2 LAST BOM_COST MIO_VRD_SB
J 0
(1125 -225);
DISPLAY 0.617021 (1125 -225);
PAINT PURPLE (1125 -225);
DISPLAY INVISIBLE (1125 -225);
FORCEPROP 2 LAST CDS_LIB pure_quanta_power
J 0
(1125 -325);
DISPLAY INVISIBLE (1125 -325);
FORCEPROP 1 LAST PATH I41
J 0
(1175 -300);
DISPLAY 0.872340 (1175 -300);
PAINT AQUA (1175 -300);
DISPLAY INVISIBLE (1175 -300);
FORCEADD OFFPAGE..4
(2275 -1775);
FORCEPROP 2 LAST $XR2 265 
J 0
(2701 -1775);
DISPLAY 0.638298 (2701 -1775);
PAINT MONO (2701 -1775);
FORCEPROP 2 LAST $XR1 264 
J 0
(2581 -1775);
DISPLAY 0.638298 (2581 -1775);
PAINT MONO (2581 -1775);
FORCEPROP 2 LAST $XR0 263 
J 0
(2461 -1775);
DISPLAY 0.638298 (2461 -1775);
PAINT MONO (2461 -1775);
FORCEPROP 2 LAST CDS_LIB standard
J 0
(2275 -1775);
DISPLAY INVISIBLE (2275 -1775);
FORCEPROP 1 LAST OFFPAGE TRUE
J 0
(2600 -1900);
DISPLAY 0.872340 (2600 -1900);
PAINT GREEN (2600 -1900);
DISPLAY INVISIBLE (2600 -1900);
FORCEPROP 1 LAST COMMENT_BODY TRUE
J 0
(2250 -1875);
DISPLAY 0.872340 (2250 -1875);
PAINT GREEN (2250 -1875);
DISPLAY INVISIBLE (2250 -1875);
FORCEPROP 2 LAST PATH I42
J 0
(2725 -1725);
DISPLAY 1.021277 (2725 -1725);
DISPLAY INVISIBLE (2725 -1725);
FORCEADD OFFPAGE..5
R 2
(2275 -1575);
FORCEPROP 2 LAST $XR2 263 
J 0
(2704 -1575);
DISPLAY 0.638298 (2704 -1575);
PAINT MONO (2704 -1575);
FORCEPROP 2 LAST $XR1 265 
J 0
(2584 -1575);
DISPLAY 0.638298 (2584 -1575);
PAINT MONO (2584 -1575);
FORCEPROP 2 LAST $XR0 264 
J 0
(2464 -1575);
DISPLAY 0.638298 (2464 -1575);
PAINT MONO (2464 -1575);
FORCEPROP 2 LAST CDS_LIB standard
J 2
(2275 -1575);
DISPLAY INVISIBLE (2275 -1575);
FORCEPROP 1 LAST OFFPAGE TRUE
J 2
(1950 -1700);
DISPLAY 0.872340 (1950 -1700);
PAINT AQUA (1950 -1700);
DISPLAY INVISIBLE (1950 -1700);
FORCEPROP 1 LAST COMMENT_BODY TRUE
J 2
(2175 -1650);
DISPLAY 1.170213 (2175 -1650);
PAINT GREEN (2175 -1650);
DISPLAY INVISIBLE (2175 -1650);
FORCEPROP 2 LAST PATH I43
J 0
(2725 -1525);
DISPLAY 1.021277 (2725 -1525);
DISPLAY INVISIBLE (2725 -1525);
FORCEADD OFFPAGE..5
R 2
(2275 -1675);
FORCEPROP 2 LAST $XR2 263 
J 0
(2704 -1675);
DISPLAY 0.638298 (2704 -1675);
PAINT MONO (2704 -1675);
FORCEPROP 2 LAST $XR1 265 
J 0
(2584 -1675);
DISPLAY 0.638298 (2584 -1675);
PAINT MONO (2584 -1675);
FORCEPROP 2 LAST $XR0 264 
J 0
(2464 -1675);
DISPLAY 0.638298 (2464 -1675);
PAINT MONO (2464 -1675);
FORCEPROP 2 LAST CDS_LIB standard
J 2
(2275 -1675);
DISPLAY INVISIBLE (2275 -1675);
FORCEPROP 1 LAST OFFPAGE TRUE
J 2
(1950 -1800);
DISPLAY 0.872340 (1950 -1800);
PAINT AQUA (1950 -1800);
DISPLAY INVISIBLE (1950 -1800);
FORCEPROP 1 LAST COMMENT_BODY TRUE
J 2
(2175 -1750);
DISPLAY 1.170213 (2175 -1750);
PAINT GREEN (2175 -1750);
DISPLAY INVISIBLE (2175 -1750);
FORCEPROP 2 LAST PATH I44
J 0
(2725 -1625);
DISPLAY 1.021277 (2725 -1625);
DISPLAY INVISIBLE (2725 -1625);
FORCEADD OFFPAGE..4
(2275 -1375);
FORCEPROP 2 LAST $XR2 265 
J 0
(2701 -1375);
DISPLAY 0.638298 (2701 -1375);
PAINT MONO (2701 -1375);
FORCEPROP 2 LAST $XR1 264 
J 0
(2581 -1375);
DISPLAY 0.638298 (2581 -1375);
PAINT MONO (2581 -1375);
FORCEPROP 2 LAST $XR0 263 
J 0
(2461 -1375);
DISPLAY 0.638298 (2461 -1375);
PAINT MONO (2461 -1375);
FORCEPROP 2 LAST CDS_LIB standard
J 0
(2275 -1375);
DISPLAY INVISIBLE (2275 -1375);
FORCEPROP 1 LAST OFFPAGE TRUE
J 0
(2600 -1500);
DISPLAY 0.872340 (2600 -1500);
PAINT GREEN (2600 -1500);
DISPLAY INVISIBLE (2600 -1500);
FORCEPROP 1 LAST COMMENT_BODY TRUE
J 0
(2250 -1475);
DISPLAY 0.872340 (2250 -1475);
PAINT GREEN (2250 -1475);
DISPLAY INVISIBLE (2250 -1475);
FORCEPROP 2 LAST PATH I45
J 0
(2725 -1325);
DISPLAY 1.021277 (2725 -1325);
DISPLAY INVISIBLE (2725 -1325);
FORCEADD OFFPAGE..5
R 2
(2275 -1200);
FORCEPROP 2 LAST $XR2 263 
J 0
(2704 -1200);
DISPLAY 0.638298 (2704 -1200);
PAINT MONO (2704 -1200);
FORCEPROP 2 LAST $XR1 265 
J 0
(2584 -1200);
DISPLAY 0.638298 (2584 -1200);
PAINT MONO (2584 -1200);
FORCEPROP 2 LAST $XR0 264 
J 0
(2464 -1200);
DISPLAY 0.638298 (2464 -1200);
PAINT MONO (2464 -1200);
FORCEPROP 2 LAST CDS_LIB standard
J 0
(2275 -1200);
DISPLAY INVISIBLE (2275 -1200);
FORCEPROP 1 LAST OFFPAGE TRUE
J 2
(1950 -1325);
DISPLAY 0.872340 (1950 -1325);
PAINT AQUA (1950 -1325);
DISPLAY INVISIBLE (1950 -1325);
FORCEPROP 1 LAST COMMENT_BODY TRUE
J 2
(2175 -1275);
DISPLAY 1.170213 (2175 -1275);
PAINT GREEN (2175 -1275);
DISPLAY INVISIBLE (2175 -1275);
FORCEPROP 2 LAST PATH I46
J 0
(2725 -1150);
DISPLAY 1.021277 (2725 -1150);
DISPLAY INVISIBLE (2725 -1150);
FORCEADD Q_CAP..1
(1000 850);
FORCEPROP 1 LAST LOCATION PC2226
J 0
(1050 925);
DISPLAY 0.723404 (1050 925);
PAINT AQUA (1050 925);
FORCEPROP 0 LAST $SEC 1
J 0
(1050 975);
DISPLAY 0.680851 (1050 975);
PAINT MONO (1050 975);
DISPLAY INVISIBLE (1050 975);
FORCEPROP 0 LAST CDS_SEC 1
J 0
(1050 975);
DISPLAY 1.021277 (1050 975);
DISPLAY INVISIBLE (1050 975);
FORCEPROP 1 LASTPIN (1000 950) $PN 1
J 0
(1010 930);
DISPLAY 0.787234 (1010 930);
PAINT MONO (1010 930);
FORCEPROP 1 LASTPIN (1000 750) $PN 2
J 0
(1010 730);
DISPLAY 0.787234 (1010 730);
PAINT MONO (1010 730);
FORCEPROP 0 LAST ROOM HSC BOM1
J 0
(1050 625);
DISPLAY 0.680851 (1050 625);
FORCEPROP 1 LAST VALUE 0.068UF
J 0
(1050 875);
DISPLAY 0.723404 (1050 875);
PAINT SKYBLUE (1050 875);
FORCEPROP 1 LAST VOLTAGE 16V
J 0
(1050 825);
DISPLAY 0.723404 (1050 825);
PAINT SKYBLUE (1050 825);
FORCEPROP 1 LAST MATERIAL X7R
J 0
(1050 775);
DISPLAY 0.723404 (1050 775);
PAINT SKYBLUE (1050 775);
FORCEPROP 1 LAST PACK_TYPE 0402
J 0
(1050 675);
DISPLAY 0.723404 (1050 675);
PAINT SKYBLUE (1050 675);
FORCEPROP 2 LAST CDS_LIB pure_quanta
J 0
(1000 850);
DISPLAY INVISIBLE (1000 850);
FORCEPROP 1 LAST TOLERANCE 10%
J 0
(1050 800);
DISPLAY 0.978723 (1050 800);
PAINT SKYBLUE (1050 800);
DISPLAY INVISIBLE (1050 800);
FORCEPROP 1 LAST PATH I47
J 0
(1050 1000);
DISPLAY 0.978723 (1050 1000);
PAINT WHITE (1050 1000);
DISPLAY INVISIBLE (1050 1000);
FORCEPROP 1 LAST PART_NUMBER CH3683K1B09
J 0
(1050 725);
DISPLAY 0.723404 (1050 725);
PAINT WHITE (1050 725);
DISPLAY INVISIBLE (1050 725);
FORCEADD UNIVERSAL_GND..1
(1000 625);
FORCEPROP 3 LASTPIN (1000 675) SIG_NAME AGND_HSC\g
J 0
(1010 685);
DISPLAY 0.659574 (1010 685);
PAINT MONO (1010 685);
DISPLAY INVISIBLE (1010 685);
FORCEPROP 1 LAST HDL_POWER AGND_HSC
J 1
(1025 550);
DISPLAY 0.723404 (1025 550);
PAINT GREEN (1025 550);
FORCEPROP 2 LAST CDS_LIB pure_quanta_power
J 0
(1000 625);
DISPLAY INVISIBLE (1000 625);
FORCEPROP 1 LAST PATH I48
J 0
(1075 625);
DISPLAY 0.872340 (1075 625);
PAINT AQUA (1075 625);
DISPLAY INVISIBLE (1075 625);
FORCEADD Q_RES..1
(1500 1400);
FORCEPROP 1 LAST LOCATION PR3993
J 0
(1200 1400);
DISPLAY 0.723404 (1200 1400);
PAINT AQUA (1200 1400);
FORCEPROP 0 LAST $SEC 1
J 0
(1650 1475);
DISPLAY 0.680851 (1650 1475);
PAINT MONO (1650 1475);
DISPLAY INVISIBLE (1650 1475);
FORCEPROP 0 LAST CDS_SEC 1
J 0
(1650 1475);
DISPLAY 1.021277 (1650 1475);
DISPLAY INVISIBLE (1650 1475);
FORCEPROP 1 LASTPIN (1400 1400) $PN 1
J 0
(1412 1412);
DISPLAY 0.787234 (1412 1412);
PAINT MONO (1412 1412);
FORCEPROP 1 LASTPIN (1600 1400) $PN 2
J 0
(1562 1412);
DISPLAY 0.787234 (1562 1412);
PAINT MONO (1562 1412);
FORCEPROP 0 LAST ROOM HSC BOM1
J 0
(1750 1350);
DISPLAY 0.553191 (1750 1350);
FORCEPROP 1 LAST VALUE 0
J 2
(1650 1425);
DISPLAY 0.723404 (1650 1425);
PAINT SKYBLUE (1650 1425);
FORCEPROP 1 LAST WATTAGE 1/16W
J 2
(1375 1300);
DISPLAY 0.723404 (1375 1300);
PAINT SKYBLUE (1375 1300);
FORCEPROP 1 LAST TOLERANCE 5%
J 0
(1625 1350);
DISPLAY 0.723404 (1625 1350);
PAINT SKYBLUE (1625 1350);
FORCEPROP 1 LAST MATERIAL CHIP
J 0
(1675 1300);
DISPLAY 0.723404 (1675 1300);
PAINT SKYBLUE (1675 1300);
FORCEPROP 1 LAST PACK_TYPE 0402LF
J 0
(1425 1300);
DISPLAY 0.723404 (1425 1300);
PAINT SKYBLUE (1425 1300);
FORCEPROP 2 LAST CDS_LIB pure_quanta
J 0
(1500 1400);
DISPLAY INVISIBLE (1500 1400);
FORCEPROP 1 LAST PATH I49
J 0
(1450 1550);
DISPLAY 0.978723 (1450 1550);
PAINT WHITE (1450 1550);
DISPLAY INVISIBLE (1450 1550);
FORCEPROP 1 LAST PART_NUMBER CS00002JB13
J 0
(1175 1350);
DISPLAY 0.723404 (1175 1350);
PAINT WHITE (1175 1350);
DISPLAY INVISIBLE (1175 1350);
FORCEADD OFFPAGE..4
R 2
(-2900 -1425);
FORCEPROP 2 LAST $XR2 265 
J 0
(-3152 -1461);
DISPLAY 0.638298 (-3152 -1461);
PAINT MONO (-3152 -1461);
FORCEPROP 2 LAST $XR1 264 
J 0
(-3272 -1425);
DISPLAY 0.638298 (-3272 -1425);
PAINT MONO (-3272 -1425);
FORCEPROP 2 LAST $XR0 263 
J 0
(-3152 -1425);
DISPLAY 0.638298 (-3152 -1425);
PAINT MONO (-3152 -1425);
FORCEPROP 2 LAST CDS_LIB standard
J 0
(-2900 -1425);
DISPLAY INVISIBLE (-2900 -1425);
FORCEPROP 1 LAST OFFPAGE TRUE
J 2
(-3225 -1550);
DISPLAY 0.872340 (-3225 -1550);
PAINT GREEN (-3225 -1550);
DISPLAY INVISIBLE (-3225 -1550);
FORCEPROP 1 LAST COMMENT_BODY TRUE
J 2
(-2875 -1525);
DISPLAY 0.872340 (-2875 -1525);
PAINT GREEN (-2875 -1525);
DISPLAY INVISIBLE (-2875 -1525);
FORCEPROP 2 LAST PATH I5
J 0
(-3150 -1375);
DISPLAY 1.021277 (-3150 -1375);
DISPLAY INVISIBLE (-3150 -1375);
FORCEADD Q_RES..1
(1500 1575);
FORCEPROP 1 LAST LOCATION PR3992
J 0
(1200 1575);
DISPLAY 0.723404 (1200 1575);
PAINT AQUA (1200 1575);
FORCEPROP 0 LAST $SEC 1
J 0
(1650 1650);
DISPLAY 0.680851 (1650 1650);
PAINT MONO (1650 1650);
DISPLAY INVISIBLE (1650 1650);
FORCEPROP 0 LAST CDS_SEC 1
J 0
(1650 1650);
DISPLAY 1.021277 (1650 1650);
DISPLAY INVISIBLE (1650 1650);
FORCEPROP 1 LASTPIN (1400 1575) $PN 1
J 0
(1412 1587);
DISPLAY 0.787234 (1412 1587);
PAINT MONO (1412 1587);
FORCEPROP 1 LASTPIN (1600 1575) $PN 2
J 0
(1562 1587);
DISPLAY 0.787234 (1562 1587);
PAINT MONO (1562 1587);
FORCEPROP 1 LAST WATTAGE 1/16W
J 2
(1375 1475);
DISPLAY 0.723404 (1375 1475);
PAINT SKYBLUE (1375 1475);
FORCEPROP 1 LAST PACK_TYPE 0402LF
J 0
(1425 1475);
DISPLAY 0.723404 (1425 1475);
PAINT SKYBLUE (1425 1475);
FORCEPROP 0 LAST ROOM HSC BOM1
J 0
(1400 1650);
DISPLAY 0.680851 (1400 1650);
FORCEPROP 1 LAST VALUE 0
J 2
(1650 1600);
DISPLAY 0.723404 (1650 1600);
PAINT SKYBLUE (1650 1600);
FORCEPROP 1 LAST TOLERANCE 5%
J 0
(1625 1525);
DISPLAY 0.723404 (1625 1525);
PAINT SKYBLUE (1625 1525);
FORCEPROP 1 LAST MATERIAL CHIP
J 0
(1675 1475);
DISPLAY 0.723404 (1675 1475);
PAINT SKYBLUE (1675 1475);
FORCEPROP 2 LAST CDS_LIB pure_quanta
J 0
(1500 1575);
DISPLAY INVISIBLE (1500 1575);
FORCEPROP 1 LAST PATH I50
J 0
(1450 1725);
DISPLAY 0.978723 (1450 1725);
PAINT WHITE (1450 1725);
DISPLAY INVISIBLE (1450 1725);
FORCEPROP 1 LAST PART_NUMBER CS00002JB13
J 0
(1175 1525);
DISPLAY 0.723404 (1175 1525);
PAINT WHITE (1175 1525);
DISPLAY INVISIBLE (1175 1525);
FORCEADD UNIVERSAL_POWER..1
(1125 2450);
FORCEPROP 3 LASTPIN (1125 2400) SIG_NAME P12V_AUX\g
J 0
(1135 2410);
DISPLAY 0.659574 (1135 2410);
PAINT MONO (1135 2410);
DISPLAY INVISIBLE (1135 2410);
FORCEPROP 1 LAST HDL_POWER P12V_AUX
J 1
(1125 2500);
DISPLAY 0.723404 (1125 2500);
PAINT GREEN (1125 2500);
FORCEPROP 2 LAST BOM_COST MIO_VRD_SB
J 0
(1125 2550);
DISPLAY 0.617021 (1125 2550);
PAINT PURPLE (1125 2550);
DISPLAY INVISIBLE (1125 2550);
FORCEPROP 2 LAST CDS_LIB pure_quanta_power
J 0
(1125 2450);
DISPLAY INVISIBLE (1125 2450);
FORCEPROP 1 LAST PATH I51
J 0
(1175 2475);
DISPLAY 0.872340 (1175 2475);
PAINT AQUA (1175 2475);
DISPLAY INVISIBLE (1175 2475);
FORCEADD OFFPAGE..4
(2300 1000);
FORCEPROP 2 LAST $XR2 265 
J 0
(2726 1000);
DISPLAY 0.638298 (2726 1000);
PAINT MONO (2726 1000);
FORCEPROP 2 LAST $XR1 264 
J 0
(2606 1000);
DISPLAY 0.638298 (2606 1000);
PAINT MONO (2606 1000);
FORCEPROP 2 LAST $XR0 263 
J 0
(2486 1000);
DISPLAY 0.638298 (2486 1000);
PAINT MONO (2486 1000);
FORCEPROP 2 LAST CDS_LIB standard
J 0
(2300 1000);
DISPLAY INVISIBLE (2300 1000);
FORCEPROP 1 LAST OFFPAGE TRUE
J 0
(2625 875);
DISPLAY 0.872340 (2625 875);
PAINT GREEN (2625 875);
DISPLAY INVISIBLE (2625 875);
FORCEPROP 1 LAST COMMENT_BODY TRUE
J 0
(2275 900);
DISPLAY 0.872340 (2275 900);
PAINT GREEN (2275 900);
DISPLAY INVISIBLE (2275 900);
FORCEPROP 2 LAST PATH I52
J 0
(2750 1050);
DISPLAY 1.021277 (2750 1050);
DISPLAY INVISIBLE (2750 1050);
FORCEADD OFFPAGE..5
R 2
(2300 1100);
FORCEPROP 2 LAST $XR2 263 
J 0
(2729 1100);
DISPLAY 0.638298 (2729 1100);
PAINT MONO (2729 1100);
FORCEPROP 2 LAST $XR1 265 
J 0
(2609 1100);
DISPLAY 0.638298 (2609 1100);
PAINT MONO (2609 1100);
FORCEPROP 2 LAST $XR0 264 
J 0
(2489 1100);
DISPLAY 0.638298 (2489 1100);
PAINT MONO (2489 1100);
FORCEPROP 2 LAST CDS_LIB standard
J 2
(2300 1100);
DISPLAY INVISIBLE (2300 1100);
FORCEPROP 1 LAST OFFPAGE TRUE
J 2
(1975 975);
DISPLAY 0.872340 (1975 975);
PAINT AQUA (1975 975);
DISPLAY INVISIBLE (1975 975);
FORCEPROP 1 LAST COMMENT_BODY TRUE
J 2
(2200 1025);
DISPLAY 1.170213 (2200 1025);
PAINT GREEN (2200 1025);
DISPLAY INVISIBLE (2200 1025);
FORCEPROP 2 LAST PATH I53
J 0
(2750 1150);
DISPLAY 1.021277 (2750 1150);
DISPLAY INVISIBLE (2750 1150);
FORCEADD OFFPAGE..5
R 2
(2300 1200);
FORCEPROP 2 LAST $XR2 263 
J 0
(2729 1200);
DISPLAY 0.638298 (2729 1200);
PAINT MONO (2729 1200);
FORCEPROP 2 LAST $XR1 265 
J 0
(2609 1200);
DISPLAY 0.638298 (2609 1200);
PAINT MONO (2609 1200);
FORCEPROP 2 LAST $XR0 264 
J 0
(2489 1200);
DISPLAY 0.638298 (2489 1200);
PAINT MONO (2489 1200);
FORCEPROP 2 LAST CDS_LIB standard
J 2
(2300 1200);
DISPLAY INVISIBLE (2300 1200);
FORCEPROP 1 LAST OFFPAGE TRUE
J 2
(1975 1075);
DISPLAY 0.872340 (1975 1075);
PAINT AQUA (1975 1075);
DISPLAY INVISIBLE (1975 1075);
FORCEPROP 1 LAST COMMENT_BODY TRUE
J 2
(2200 1125);
DISPLAY 1.170213 (2200 1125);
PAINT GREEN (2200 1125);
DISPLAY INVISIBLE (2200 1125);
FORCEPROP 2 LAST PATH I54
J 0
(2750 1250);
DISPLAY 1.021277 (2750 1250);
DISPLAY INVISIBLE (2750 1250);
FORCEADD OFFPAGE..4
(2300 1400);
FORCEPROP 2 LAST $XR2 265 
J 0
(2726 1400);
DISPLAY 0.638298 (2726 1400);
PAINT MONO (2726 1400);
FORCEPROP 2 LAST $XR1 264 
J 0
(2606 1400);
DISPLAY 0.638298 (2606 1400);
PAINT MONO (2606 1400);
FORCEPROP 2 LAST $XR0 263 
J 0
(2486 1400);
DISPLAY 0.638298 (2486 1400);
PAINT MONO (2486 1400);
FORCEPROP 2 LAST CDS_LIB standard
J 0
(2300 1400);
DISPLAY INVISIBLE (2300 1400);
FORCEPROP 1 LAST OFFPAGE TRUE
J 0
(2625 1275);
DISPLAY 0.872340 (2625 1275);
PAINT GREEN (2625 1275);
DISPLAY INVISIBLE (2625 1275);
FORCEPROP 1 LAST COMMENT_BODY TRUE
J 0
(2275 1300);
DISPLAY 0.872340 (2275 1300);
PAINT GREEN (2275 1300);
DISPLAY INVISIBLE (2275 1300);
FORCEPROP 2 LAST PATH I55
J 0
(2750 1450);
DISPLAY 1.021277 (2750 1450);
DISPLAY INVISIBLE (2750 1450);
FORCEADD OFFPAGE..5
R 2
(2300 1575);
FORCEPROP 2 LAST $XR2 263 
J 0
(2729 1575);
DISPLAY 0.638298 (2729 1575);
PAINT MONO (2729 1575);
FORCEPROP 2 LAST $XR1 265 
J 0
(2609 1575);
DISPLAY 0.638298 (2609 1575);
PAINT MONO (2609 1575);
FORCEPROP 2 LAST $XR0 264 
J 0
(2489 1575);
DISPLAY 0.638298 (2489 1575);
PAINT MONO (2489 1575);
FORCEPROP 2 LAST CDS_LIB standard
J 0
(2300 1575);
DISPLAY INVISIBLE (2300 1575);
FORCEPROP 1 LAST OFFPAGE TRUE
J 2
(1975 1450);
DISPLAY 0.872340 (1975 1450);
PAINT AQUA (1975 1450);
DISPLAY INVISIBLE (1975 1450);
FORCEPROP 1 LAST COMMENT_BODY TRUE
J 2
(2200 1500);
DISPLAY 1.170213 (2200 1500);
PAINT GREEN (2200 1500);
DISPLAY INVISIBLE (2200 1500);
FORCEPROP 2 LAST PATH I56
J 0
(2750 1625);
DISPLAY 1.021277 (2750 1625);
DISPLAY INVISIBLE (2750 1625);
FORCEADD Q_RES..1
R 1
(-3575 -825);
FORCEPROP 1 LAST LOCATION PR3981
J 0
(-3500 -675);
DISPLAY 0.723404 (-3500 -675);
PAINT AQUA (-3500 -675);
FORCEPROP 0 LAST $SEC 1
R 1
J 0
(-3500 -625);
DISPLAY 0.680851 (-3500 -625);
PAINT MONO (-3500 -625);
DISPLAY INVISIBLE (-3500 -625);
FORCEPROP 0 LAST CDS_SEC 1
R 1
J 0
(-3500 -625);
DISPLAY 1.021277 (-3500 -625);
DISPLAY INVISIBLE (-3500 -625);
FORCEPROP 1 LASTPIN (-3575 -925) $PN 1
R 1
J 0
(-3587 -913);
DISPLAY 0.787234 (-3587 -913);
PAINT MONO (-3587 -913);
FORCEPROP 1 LASTPIN (-3575 -725) $PN 2
R 1
J 0
(-3587 -763);
DISPLAY 0.787234 (-3587 -763);
PAINT MONO (-3587 -763);
FORCEPROP 1 LAST PACK_TYPE 0402LF
J 0
(-3500 -975);
DISPLAY 0.723404 (-3500 -975);
PAINT SKYBLUE (-3500 -975);
FORCEPROP 1 LAST VALUE 0
R 2
J 0
(-3475 -700);
DISPLAY 0.723404 (-3475 -700);
PAINT SKYBLUE (-3475 -700);
FORCEPROP 1 LAST TOLERANCE 5%
J 0
(-3500 -775);
DISPLAY 0.723404 (-3500 -775);
PAINT SKYBLUE (-3500 -775);
FORCEPROP 1 LAST WATTAGE 1/16W
J 0
(-3500 -875);
DISPLAY 0.723404 (-3500 -875);
PAINT SKYBLUE (-3500 -875);
FORCEPROP 1 LAST MATERIAL CHIP
J 0
(-3500 -825);
DISPLAY 0.787234 (-3500 -825);
PAINT SKYBLUE (-3500 -825);
FORCEPROP 0 LAST ROOM HSC BOM1
J 0
(-3500 -600);
DISPLAY 0.680851 (-3500 -600);
FORCEPROP 2 LAST CDS_LIB pure_quanta
J 0
(-3575 -825);
DISPLAY INVISIBLE (-3575 -825);
FORCEPROP 1 LAST PATH I6
R 1
J 0
(-3725 -875);
DISPLAY 0.978723 (-3725 -875);
PAINT WHITE (-3725 -875);
DISPLAY INVISIBLE (-3725 -875);
FORCEPROP 1 LAST PART_NUMBER CS00002JB13
J 0
(-3500 -925);
DISPLAY 0.723404 (-3500 -925);
PAINT WHITE (-3500 -925);
DISPLAY INVISIBLE (-3500 -925);
FORCEADD UNIVERSAL_POWER..1
(-3575 -575);
FORCEPROP 3 LASTPIN (-3575 -625) SIG_NAME HSC_VDD\g
J 0
(-3565 -615);
DISPLAY 0.659574 (-3565 -615);
PAINT MONO (-3565 -615);
DISPLAY INVISIBLE (-3565 -615);
FORCEPROP 1 LAST HDL_POWER HSC_VDD
J 1
(-3575 -525);
DISPLAY 0.723404 (-3575 -525);
PAINT GREEN (-3575 -525);
FORCEPROP 2 LAST BOM_COST MIO_VRD_SB
J 0
(-3575 -475);
DISPLAY 0.617021 (-3575 -475);
PAINT PURPLE (-3575 -475);
DISPLAY INVISIBLE (-3575 -475);
FORCEPROP 2 LAST CDS_LIB pure_quanta_power
J 0
(-3575 -575);
DISPLAY INVISIBLE (-3575 -575);
FORCEPROP 1 LAST PATH I7
J 0
(-3525 -550);
DISPLAY 0.872340 (-3525 -550);
PAINT AQUA (-3525 -550);
DISPLAY INVISIBLE (-3525 -550);
FORCEADD UNIVERSAL_GND..1
(-2700 -1225);
FORCEPROP 3 LASTPIN (-2700 -1175) SIG_NAME AGND_HSC\g
J 0
(-2690 -1165);
DISPLAY 0.659574 (-2690 -1165);
PAINT MONO (-2690 -1165);
DISPLAY INVISIBLE (-2690 -1165);
FORCEPROP 1 LAST HDL_POWER AGND_HSC
J 1
(-2675 -1300);
DISPLAY 0.723404 (-2675 -1300);
PAINT GREEN (-2675 -1300);
FORCEPROP 2 LAST CDS_LIB pure_quanta_power
J 0
(-2700 -1225);
DISPLAY INVISIBLE (-2700 -1225);
FORCEPROP 1 LAST PATH I8
J 0
(-2625 -1225);
DISPLAY 0.872340 (-2625 -1225);
PAINT AQUA (-2625 -1225);
DISPLAY INVISIBLE (-2625 -1225);
FORCEADD OFFPAGE..4
R 2
(-2075 -1525);
FORCEPROP 2 LAST $XR2 265 
J 0
(-2597 -1525);
DISPLAY 0.638298 (-2597 -1525);
PAINT MONO (-2597 -1525);
FORCEPROP 2 LAST $XR1 264 
J 0
(-2477 -1525);
DISPLAY 0.638298 (-2477 -1525);
PAINT MONO (-2477 -1525);
FORCEPROP 2 LAST $XR0 263 
J 0
(-2357 -1525);
DISPLAY 0.638298 (-2357 -1525);
PAINT MONO (-2357 -1525);
FORCEPROP 2 LAST CDS_LIB standard
J 0
(-2075 -1525);
DISPLAY INVISIBLE (-2075 -1525);
FORCEPROP 1 LAST OFFPAGE TRUE
J 2
(-2400 -1650);
DISPLAY 0.872340 (-2400 -1650);
PAINT GREEN (-2400 -1650);
DISPLAY INVISIBLE (-2400 -1650);
FORCEPROP 1 LAST COMMENT_BODY TRUE
J 2
(-2050 -1625);
DISPLAY 0.872340 (-2050 -1625);
PAINT GREEN (-2050 -1625);
DISPLAY INVISIBLE (-2050 -1625);
FORCEPROP 2 LAST PATH I9
J 0
(-2350 -1475);
DISPLAY 1.021277 (-2350 -1475);
DISPLAY INVISIBLE (-2350 -1475);
FORCEADD QUANTA_TITLE_BLOCK_C..1
(4725 -3325);
FORCEPROP 0 LAST CDS_CON_LAST_MODIFIED Thu Sep 14 16:12:22 2023
J 0
(2840 -3310);
PAINT MONO (2840 -3310);
DISPLAY INVISIBLE (2840 -3310);
FORCEPROP 2 LAST CUSTOM_TXT_CDS <XR_PAGE_TITLE>
J 0
(-3165 1925);
DISPLAY 0.638298 (-3165 1925);
PAINT PINK (-3165 1925);
DISPLAY INVISIBLE (-3165 1925);
FORCEPROP 2 LAST CUSTOM_TXT_CDS <CON_LAST_MODIFIED>
J 0
(2840 -3310);
DISPLAY 0.978723 (2840 -3310);
FORCEPROP 2 LAST CUSTOM_TXT_CDS <Q_NUMBER>
J 0
(3322 -3222);
DISPLAY 1.212766 (3322 -3222);
FORCEPROP 2 LAST CUSTOM_TXT_CDS <Q_PROJ>
J 0
(2343 -3223);
DISPLAY 1.212766 (2343 -3223);
FORCEPROP 2 LAST CUSTOM_TXT_CDS <CON_PAGE_NUM> OF <CON_TOTAL_PAGES>
J 0
(4279 -3307);
DISPLAY 0.978723 (4279 -3307);
FORCEPROP 2 LAST CUSTOM_TXT_CDS <Q_REV>
J 0
(4541 -3222);
DISPLAY 1.212766 (4541 -3222);
FORCEPROP 1 LAST CUSTOM_TXT_CDS <NAME_2>
J 0
(1550 -3275);
FORCEPROP 1 LAST CUSTOM_TXT_CDS <NAME_1>
J 0
(1550 -3150);
FORCEPROP 1 LAST Q_TITLE HSC MP5990 (3/3)
J 0
(-4641 -3299);
DISPLAY 2.446809 (-4641 -3299);
PAINT GREEN (-4641 -3299);
FORCEPROP 1 LAST CDS_LMAN_SYM_OUTLINE -9475,6775,100,-125
J 0
(4725 -3325);
DISPLAY 0.468085 (4725 -3325);
PAINT GREEN (4725 -3325);
DISPLAY INVISIBLE (4725 -3325);
FORCEPROP 2 LAST CDS_LIB pure_quanta
J 0
(4725 -3325);
PAINT MONO (4725 -3325);
DISPLAY INVISIBLE (4725 -3325);
FORCEPROP 2 LAST PAGE_BORDER TRUE
J 0
(-3165 1925);
DISPLAY 0.638298 (-3165 1925);
PAINT PINK (-3165 1925);
DISPLAY INVISIBLE (-3165 1925);
FORCEPROP 2 LAST CDS_XR_PAGE_TITLE CR-265 : @T6G_MB_LIB.T6G(SCH_1):PAGE265
J 0
(-3165 1925);
DISPLAY 0.638298 (-3165 1925);
PAINT PINK (-3165 1925);
DISPLAY INVISIBLE (-3165 1925);
FORCEPROP 1 LAST Q_DEPT BU9
J 1
(962 -3276);
DISPLAY 1.957447 (962 -3276);
PAINT GREEN (962 -3276);
DISPLAY INVISIBLE (962 -3276);
FORCEPROP 1 LAST COMMENT_BODY TRUE
J 0
(4737 -3338);
DISPLAY 0.978723 (4737 -3338);
PAINT GREEN (4737 -3338);
DISPLAY INVISIBLE (4737 -3338);
FORCEADD DNS..2
(-1925 825);
PAINT RED (-1925 825);
FORCEPROP 2 LAST CDS_LIB mstr_misc
J 0
(-1925 825);
DISPLAY INVISIBLE (-1925 825);
FORCEPROP 1 LAST COMMENT_BODY TRUE
R 1
J 0
(-1850 600);
DISPLAY 0.872340 (-1850 600);
PAINT GREEN (-1850 600);
DISPLAY INVISIBLE (-1850 600);
FORCEADD DNS..2
(-2700 850);
PAINT RED (-2700 850);
FORCEPROP 2 LAST CDS_LIB mstr_misc
J 0
(-2700 850);
DISPLAY INVISIBLE (-2700 850);
FORCEPROP 1 LAST COMMENT_BODY TRUE
R 1
J 0
(-2625 625);
DISPLAY 0.872340 (-2625 625);
PAINT GREEN (-2625 625);
DISPLAY INVISIBLE (-2625 625);
FORCEADD DNS..2
(-1975 -1925);
PAINT RED (-1975 -1925);
FORCEPROP 2 LAST CDS_LIB mstr_misc
J 0
(-1975 -1925);
DISPLAY INVISIBLE (-1975 -1925);
FORCEPROP 1 LAST COMMENT_BODY TRUE
R 1
J 0
(-1900 -2150);
DISPLAY 0.872340 (-1900 -2150);
PAINT GREEN (-1900 -2150);
DISPLAY INVISIBLE (-1900 -2150);
FORCEADD DNS..2
(-2675 -1950);
PAINT RED (-2675 -1950);
FORCEPROP 2 LAST CDS_LIB mstr_misc
J 0
(-2675 -1950);
DISPLAY INVISIBLE (-2675 -1950);
FORCEPROP 1 LAST COMMENT_BODY TRUE
R 1
J 0
(-2600 -2175);
DISPLAY 0.872340 (-2600 -2175);
PAINT GREEN (-2600 -2175);
DISPLAY INVISIBLE (-2600 -2175);
WIRE 16 -1 (-3600 1375)(-3600 1225);
WIRE 16 -1 (-3600 2150)(-3600 2050);
WIRE 16 -1 (-3575 -1400)(-3575 -1550);
WIRE 16 -1 (1000 -2025)(1000 -2100);
WIRE 16 -1 (1000 750)(1000 675);
WIRE 16 -1 (-3575 -625)(-3575 -725);
WIRE 16 -1 (-450 -1625)(-1475 -1625);
FORCEPROP 2 LAST SIG_NAME HSC_CS_4
J 0
(-985 -1615);
DISPLAY 0.808511 (-985 -1615);
FORCEPROP 2 LASTPROP $XRERR UNIQUE?
J 0
(-1225 -1615);
DISPLAY 0.638298 (-1225 -1615);
PAINT MONO (-1225 -1615);
DISPLAY INVISIBLE (-1225 -1615);
WIRE 16 -1 (-1475 -1625)(-1475 -1850);
WIRE 16 -1 (-1975 -2125)(-1475 -2125);
WIRE 16 -1 (-1975 -2050)(-1975 -2125);
WIRE 16 -1 (-1975 -2125)(-2700 -2125);
WIRE 16 -1 (-950 -2125)(-1475 -2125);
WIRE 16 -1 (-1475 -2050)(-1475 -2125);
WIRE 16 -1 (-950 -2050)(-950 -2125);
WIRE 16 -1 (-950 -2125)(-500 -2125);
WIRE 16 -1 (-2700 -2050)(-2700 -2125);
WIRE 16 -1 (-2700 -2200)(-2700 -2125);
WIRE 16 -1 (-500 -1925)(-500 -2125);
WIRE 16 -1 (-450 -1925)(-500 -1925);
WIRE 16 -1 (-1950 650)(-1475 650);
WIRE 16 -1 (-1950 725)(-1950 650);
WIRE 16 -1 (-1950 650)(-2700 650);
WIRE 16 -1 (-950 650)(-1475 650);
WIRE 16 -1 (-1475 725)(-1475 650);
WIRE 16 -1 (-950 650)(-500 650);
WIRE 16 -1 (-950 725)(-950 650);
WIRE 16 -1 (-2700 725)(-2700 650);
WIRE 16 -1 (-2700 575)(-2700 650);
WIRE 16 -1 (-500 850)(-500 650);
WIRE 16 -1 (-450 850)(-500 850);
WIRE 16 -1 (-1000 1050)(-950 1050);
WIRE 16 -1 (-450 1050)(-950 1050);
FORCEPROP 2 LAST SIG_NAME HSC_IMON
J 0
(-1010 1060);
DISPLAY 0.808511 (-1010 1060);
WIRE 16 -1 (-950 925)(-950 1050);
WIRE 16 -1 (-450 1150)(-1475 1150);
FORCEPROP 2 LAST SIG_NAME HSC_CS_3
J 0
(-1010 1160);
DISPLAY 0.808511 (-1010 1160);
FORCEPROP 2 LASTPROP $XRERR UNIQUE?
J 0
(-1250 1160);
DISPLAY 0.638298 (-1250 1160);
PAINT MONO (-1250 1160);
DISPLAY INVISIBLE (-1250 1160);
WIRE 16 -1 (-1475 1150)(-1475 925);
WIRE 16 -1 (-1425 1475)(-1975 1475);
FORCEPROP 2 LAST SIG_NAME HSC_SCREF
J 0
(-1985 1485);
DISPLAY 0.808511 (-1985 1485);
WIRE 16 -1 (-2725 1650)(-2000 1650);
WIRE 16 -1 (-2725 1625)(-2725 1650);
WIRE 16 -1 (-3600 1575)(-3600 1750);
WIRE 16 -1 (-3600 1750)(-450 1750);
FORCEPROP 2 LAST SIG_NAME HSC_VDD_R_3
J 0
(-1010 1760);
DISPLAY 0.808511 (-1010 1760);
FORCEPROP 2 LASTPROP $XRERR UNIQUE?
J 0
(-1250 1760);
DISPLAY 0.638298 (-1250 1760);
PAINT MONO (-1250 1760);
DISPLAY INVISIBLE (-1250 1760);
WIRE 16 -1 (-3600 1850)(-3600 1750);
WIRE 16 -1 (-450 -1225)(-875 -1225);
FORCEPROP 2 LAST SIG_NAME HSC_SCREF_4
J 0
(-985 -1215);
DISPLAY 0.808511 (-985 -1215);
FORCEPROP 2 LASTPROP $XRERR UNIQUE?
J 0
(-1225 -1215);
DISPLAY 0.638298 (-1225 -1215);
PAINT MONO (-1225 -1215);
DISPLAY INVISIBLE (-1225 -1215);
WIRE 16 -1 (-875 -1225)(-875 -1300);
WIRE 16 -1 (-875 -1300)(-1200 -1300);
WIRE 16 -1 (-1400 -1300)(-1975 -1300);
FORCEPROP 2 LAST SIG_NAME HSC_SCREF
J 0
(-1985 -1290);
DISPLAY 0.808511 (-1985 -1290);
WIRE 16 -1 (1600 -1375)(2225 -1375);
FORCEPROP 2 LAST SIG_NAME HSC_FLT_TYPE
J 0
(1715 -1365);
DISPLAY 0.808511 (1715 -1365);
WIRE 16 -1 (500 1300)(950 1300);
FORCEPROP 2 LAST SIG_NAME HSC_NC1_3
J 0
(615 1310);
DISPLAY 0.808511 (615 1310);
FORCEPROP 2 LASTPROP $XRERR UNIQUE?
J 0
(980 1300);
DISPLAY 0.638298 (980 1300);
PAINT MONO (980 1300);
DISPLAY INVISIBLE (980 1300);
WIRE 16 -1 (-450 1550)(-875 1550);
FORCEPROP 2 LAST SIG_NAME HSC_SCREF_3
J 0
(-1010 1560);
DISPLAY 0.808511 (-1010 1560);
FORCEPROP 2 LASTPROP $XRERR UNIQUE?
J 0
(-1250 1560);
DISPLAY 0.638298 (-1250 1560);
PAINT MONO (-1250 1560);
DISPLAY INVISIBLE (-1250 1560);
WIRE 16 -1 (-875 1550)(-875 1475);
WIRE 16 -1 (-875 1475)(-1225 1475);
WIRE 16 -1 (-1950 925)(-1950 1250);
WIRE 16 -1 (-1950 1250)(-450 1250);
FORCEPROP 2 LAST SIG_NAME HSC_OCREF
J 0
(-1010 1260);
DISPLAY 0.808511 (-1010 1260);
WIRE 16 -1 (-2000 1250)(-1950 1250);
WIRE 16 -1 (-450 1350)(-2700 1350);
FORCEPROP 2 LAST SIG_NAME HSC_ON
J 0
(-1010 1360);
DISPLAY 0.808511 (-1010 1360);
WIRE 16 -1 (-2825 1350)(-2700 1350);
WIRE 16 -1 (-2700 1350)(-2700 925);
WIRE 16 -1 (-1800 1650)(-450 1650);
FORCEPROP 2 LAST SIG_NAME HSC_MODE_3
J 0
(-1010 1660);
DISPLAY 0.808511 (-1010 1660);
FORCEPROP 2 LASTPROP $XRERR UNIQUE?
J 0
(-1250 1660);
DISPLAY 0.638298 (-1250 1660);
PAINT MONO (-1250 1660);
DISPLAY INVISIBLE (-1250 1660);
WIRE 16 -1 (500 1400)(1400 1400);
FORCEPROP 2 LAST SIG_NAME HSC_FLT_TYPE_3
J 0
(615 1410);
DISPLAY 0.808511 (615 1410);
FORCEPROP 2 LASTPROP $XRERR UNIQUE?
J 0
(375 1410);
DISPLAY 0.638298 (375 1410);
PAINT MONO (375 1410);
DISPLAY INVISIBLE (375 1410);
WIRE 16 -1 (625 1575)(1400 1575);
WIRE 16 -1 (625 1500)(625 1575);
FORCEPROP 2 LAST SIG_NAME HSC_D_OC_3
J 0
(615 1585);
DISPLAY 0.808511 (615 1585);
FORCEPROP 2 LASTPROP $XRERR UNIQUE?
J 0
(375 1585);
DISPLAY 0.638298 (375 1585);
PAINT MONO (375 1585);
DISPLAY INVISIBLE (375 1585);
WIRE 16 -1 (625 1500)(500 1500);
WIRE 16 -1 (1600 1575)(2250 1575);
FORCEPROP 2 LAST SIG_NAME HSC_D_OC_R
J 0
(1815 1585);
DISPLAY 0.808511 (1815 1585);
WIRE 16 -1 (1600 1400)(2250 1400);
FORCEPROP 2 LAST SIG_NAME HSC_FLT_TYPE
J 0
(1740 1410);
DISPLAY 0.808511 (1740 1410);
WIRE 16 -1 (500 1200)(2250 1200);
FORCEPROP 2 LAST SIG_NAME HSC_FAULT
J 0
(615 1210);
DISPLAY 0.808511 (615 1210);
WIRE 16 -1 (500 1100)(2250 1100);
FORCEPROP 2 LAST SIG_NAME HSC_VTEMP
J 0
(615 1110);
DISPLAY 0.808511 (615 1110);
WIRE 16 -1 (1000 1000)(2250 1000);
WIRE 16 -1 (1000 1000)(1000 950);
WIRE 16 -1 (500 1000)(1000 1000);
FORCEPROP 2 LAST SIG_NAME HSC_SS
J 0
(615 1010);
DISPLAY 0.808511 (615 1010);
WIRE 16 -1 (-450 -1425)(-2700 -1425);
FORCEPROP 2 LAST SIG_NAME HSC_ON
J 0
(-985 -1415);
DISPLAY 0.808511 (-985 -1415);
WIRE 16 -1 (-2700 -1425)(-2850 -1425);
WIRE 16 -1 (-2700 -1425)(-2700 -1850);
WIRE 16 -1 (-950 -1850)(-950 -1725);
WIRE 16 -1 (-450 -1725)(-950 -1725);
FORCEPROP 2 LAST SIG_NAME HSC_IMON
J 0
(-985 -1715);
DISPLAY 0.808511 (-985 -1715);
WIRE 16 -1 (-1000 -1725)(-950 -1725);
WIRE 16 -1 (-1975 -1850)(-1975 -1525);
WIRE 16 -1 (-450 -1525)(-1975 -1525);
FORCEPROP 2 LAST SIG_NAME HSC_OCREF
J 0
(-985 -1515);
DISPLAY 0.808511 (-985 -1515);
WIRE 16 -1 (-2025 -1525)(-1975 -1525);
WIRE 16 -1 (-1800 -1125)(-450 -1125);
FORCEPROP 2 LAST SIG_NAME HSC_MODE_4
J 0
(-985 -1115);
DISPLAY 0.808511 (-985 -1115);
FORCEPROP 2 LASTPROP $XRERR UNIQUE?
J 0
(-1225 -1115);
DISPLAY 0.638298 (-1225 -1115);
PAINT MONO (-1225 -1115);
DISPLAY INVISIBLE (-1225 -1115);
WIRE 16 -1 (-3575 -1200)(-3575 -1025);
WIRE 16 -1 (-3575 -1025)(-450 -1025);
FORCEPROP 2 LAST SIG_NAME HSC_VDD_R_4
J 0
(-985 -1015);
DISPLAY 0.808511 (-985 -1015);
FORCEPROP 2 LASTPROP $XRERR UNIQUE?
J 0
(-1225 -1015);
DISPLAY 0.638298 (-1225 -1015);
PAINT MONO (-1225 -1015);
DISPLAY INVISIBLE (-1225 -1015);
WIRE 16 -1 (-3575 -925)(-3575 -1025);
WIRE 16 -1 (-650 -875)(-450 -875);
WIRE 16 -1 (-650 -825)(-650 -875);
WIRE 16 -1 (-450 -825)(-650 -825);
WIRE 16 -1 (-650 -775)(-650 -825);
WIRE 16 -1 (-450 -775)(-650 -775);
WIRE 16 -1 (-650 -725)(-650 -775);
WIRE 16 -1 (-450 -725)(-650 -725);
WIRE 16 -1 (-650 -675)(-650 -725);
WIRE 16 -1 (-450 -675)(-650 -675);
WIRE 16 -1 (-650 -625)(-650 -675);
WIRE 16 -1 (-450 -625)(-650 -625);
WIRE 16 -1 (-650 -575)(-650 -625);
WIRE 16 -1 (-450 -575)(-650 -575);
WIRE 16 -1 (-650 -525)(-650 -575);
WIRE 16 -1 (-450 -525)(-650 -525);
WIRE 16 -1 (-650 -475)(-650 -525);
WIRE 16 -1 (-450 -475)(-650 -475);
WIRE 16 -1 (-650 -425)(-650 -475);
WIRE 16 -1 (-950 -425)(-650 -425);
WIRE 16 -1 (-950 -375)(-950 -425);
WIRE 16 -1 (-650 1900)(-450 1900);
WIRE 16 -1 (-650 1950)(-650 1900);
WIRE 16 -1 (-450 1950)(-650 1950);
WIRE 16 -1 (-650 2000)(-650 1950);
WIRE 16 -1 (-650 2050)(-650 2000);
WIRE 16 -1 (-450 2000)(-650 2000);
WIRE 16 -1 (-450 2050)(-650 2050);
WIRE 16 -1 (-650 2100)(-650 2050);
WIRE 16 -1 (-450 2100)(-650 2100);
WIRE 16 -1 (-650 2150)(-650 2100);
WIRE 16 -1 (-450 2150)(-650 2150);
WIRE 16 -1 (-650 2200)(-650 2150);
WIRE 16 -1 (-450 2200)(-650 2200);
WIRE 16 -1 (-650 2250)(-650 2200);
WIRE 16 -1 (-450 2250)(-650 2250);
WIRE 16 -1 (-650 2300)(-650 2250);
WIRE 16 -1 (-450 2300)(-650 2300);
WIRE 16 -1 (-650 2350)(-650 2300);
WIRE 16 -1 (-950 2350)(-650 2350);
WIRE 16 -1 (-950 2400)(-950 2350);
WIRE 16 -1 (625 -825)(625 -875);
WIRE 16 -1 (625 -775)(625 -825);
WIRE 16 -1 (500 -825)(625 -825);
WIRE 16 -1 (625 -875)(625 -925);
WIRE 16 -1 (500 -875)(625 -875);
WIRE 16 -1 (625 -925)(500 -925);
WIRE 16 -1 (625 -725)(625 -775);
WIRE 16 -1 (500 -775)(625 -775);
WIRE 16 -1 (625 -675)(625 -725);
WIRE 16 -1 (500 -725)(625 -725);
WIRE 16 -1 (625 -625)(625 -675);
WIRE 16 -1 (500 -675)(625 -675);
WIRE 16 -1 (625 -575)(625 -625);
WIRE 16 -1 (500 -625)(625 -625);
WIRE 16 -1 (625 -525)(625 -575);
WIRE 16 -1 (500 -575)(625 -575);
WIRE 16 -1 (625 -475)(625 -525);
WIRE 16 -1 (500 -525)(625 -525);
WIRE 16 -1 (625 -400)(625 -475);
WIRE 16 -1 (500 -475)(625 -475);
WIRE 16 -1 (1125 -400)(625 -400);
WIRE 16 -1 (1125 -375)(1125 -400);
WIRE 16 -1 (625 1950)(625 1900);
WIRE 16 -1 (625 2000)(625 1950);
WIRE 16 -1 (500 1950)(625 1950);
WIRE 16 -1 (625 1900)(625 1850);
WIRE 16 -1 (500 1900)(625 1900);
WIRE 16 -1 (625 1850)(500 1850);
WIRE 16 -1 (625 2050)(625 2000);
WIRE 16 -1 (500 2000)(625 2000);
WIRE 16 -1 (625 2100)(625 2050);
WIRE 16 -1 (500 2050)(625 2050);
WIRE 16 -1 (625 2150)(625 2100);
WIRE 16 -1 (500 2100)(625 2100);
WIRE 16 -1 (625 2200)(625 2150);
WIRE 16 -1 (500 2150)(625 2150);
WIRE 16 -1 (625 2250)(625 2200);
WIRE 16 -1 (500 2200)(625 2200);
WIRE 16 -1 (625 2300)(625 2250);
WIRE 16 -1 (500 2250)(625 2250);
WIRE 16 -1 (625 2375)(625 2300);
WIRE 16 -1 (500 2300)(625 2300);
WIRE 16 -1 (1125 2375)(625 2375);
WIRE 16 -1 (1125 2400)(1125 2375);
WIRE 16 -1 (-2700 -1125)(-2000 -1125);
WIRE 16 -1 (-2700 -1175)(-2700 -1125);
WIRE 16 -1 (1600 -1200)(2225 -1200);
FORCEPROP 2 LAST SIG_NAME HSC_D_OC_R
J 0
(1765 -1190);
DISPLAY 0.808511 (1765 -1190);
WIRE 16 -1 (575 -1275)(575 -1200);
FORCEPROP 2 LAST SIG_NAME HSC_D_OC_4
J 0
(640 -1190);
DISPLAY 0.808511 (640 -1190);
FORCEPROP 2 LASTPROP $XRERR UNIQUE?
J 0
(400 -1190);
DISPLAY 0.638298 (400 -1190);
PAINT MONO (400 -1190);
DISPLAY INVISIBLE (400 -1190);
WIRE 16 -1 (575 -1275)(500 -1275);
WIRE 16 -1 (575 -1200)(1400 -1200);
WIRE 16 -1 (500 -1775)(1000 -1775);
FORCEPROP 2 LAST SIG_NAME HSC_SS
J 0
(640 -1765);
DISPLAY 0.808511 (640 -1765);
WIRE 16 -1 (1000 -1775)(2225 -1775);
WIRE 16 -1 (1000 -1775)(1000 -1825);
WIRE 16 -1 (500 -1675)(2225 -1675);
FORCEPROP 2 LAST SIG_NAME HSC_VTEMP
J 0
(640 -1665);
DISPLAY 0.808511 (640 -1665);
WIRE 16 -1 (500 -1575)(2225 -1575);
FORCEPROP 2 LAST SIG_NAME HSC_FAULT
J 0
(640 -1565);
DISPLAY 0.808511 (640 -1565);
WIRE 16 -1 (500 -1475)(975 -1475);
FORCEPROP 2 LAST SIG_NAME HSC_NC1_4
J 0
(640 -1465);
DISPLAY 0.808511 (640 -1465);
FORCEPROP 2 LASTPROP $XRERR UNIQUE?
J 0
(1005 -1475);
DISPLAY 0.638298 (1005 -1475);
PAINT MONO (1005 -1475);
DISPLAY INVISIBLE (1005 -1475);
WIRE 16 -1 (500 -1375)(1400 -1375);
FORCEPROP 2 LAST SIG_NAME HSC_FLT_TYPE_4
J 0
(640 -1365);
DISPLAY 0.808511 (640 -1365);
FORCEPROP 2 LASTPROP $XRERR UNIQUE?
J 0
(400 -1365);
DISPLAY 0.638298 (400 -1365);
PAINT MONO (400 -1365);
DISPLAY INVISIBLE (400 -1365);
DOT 1 (625 2300);
DOT 1 (625 2200);
DOT 1 (625 2150);
DOT 1 (625 2100);
DOT 1 (625 2050);
DOT 1 (625 2000);
DOT 1 (625 1950);
DOT 1 (625 1900);
DOT 1 (1000 1000);
DOT 1 (625 -475);
DOT 1 (625 -525);
DOT 1 (625 -575);
DOT 1 (625 -625);
DOT 1 (625 -725);
DOT 1 (625 -675);
DOT 1 (625 -825);
DOT 1 (625 -775);
DOT 1 (625 -875);
DOT 1 (1000 -1775);
DOT 1 (-650 2300);
DOT 1 (-650 2250);
DOT 1 (-650 2200);
DOT 1 (-650 2150);
DOT 1 (-650 2100);
DOT 1 (-650 2000);
DOT 1 (-650 1950);
DOT 1 (-950 1050);
DOT 1 (-950 650);
DOT 1 (-1950 1250);
DOT 1 (-1950 650);
DOT 1 (-2700 1350);
DOT 1 (-3600 1750);
DOT 1 (-650 -475);
DOT 1 (-650 -525);
DOT 1 (-650 -575);
DOT 1 (-650 -625);
DOT 1 (-650 -725);
DOT 1 (-650 -675);
DOT 1 (-650 -775);
DOT 1 (-650 -825);
DOT 1 (-950 -1725);
DOT 1 (-950 -2125);
DOT 1 (-1475 -2125);
DOT 1 (-1975 -2125);
DOT 1 (-2700 -1425);
DOT 1 (-3575 -1025);
DOT 1 (-2700 -2125);
DOT 1 (-650 2050);
DOT 1 (-2700 650);
DOT 1 (-1475 650);
DOT 1 (625 2250);
DOT 1 (-1975 -1525);
FORCENOTE
VOUT SLEW RATE: 2V/MS
(1500 -2050) 0;
DISPLAY LEFT (1500 -2050);
DISPLAY 1.021277 (1500 -2050);
FORCENOTE
SOFT START TIME=6MS.
(1500 -1985) 0;
DISPLAY LEFT (1500 -1985);
DISPLAY 1.021277 (1500 -1985);
FORCENOTE
VOUT SLEW RATE: 2V/MS
(1500 725) 0;
DISPLAY LEFT (1500 725);
DISPLAY 1.021277 (1500 725);
FORCENOTE
SOFT START TIME=6MS.
(1500 791) 0;
DISPLAY LEFT (1500 791);
DISPLAY 1.021277 (1500 791);
FORCENOTE
HOT SWAT CIRCUIT
(-4496 3138) 0;
DISPLAY LEFT (-4496 3138);
DISPLAY 2.000000 (-4496 3138);
QUIT
